G04 ================== begin FILE IDENTIFICATION RECORD ==================*
G04 Layout Name:  DAT6MTH3AD0_t6m_cm_d_brd_103112_274.brd*
G04 Film Name:    gnd2*
G04 File Format:  Gerber RS274X*
G04 File Origin:  Cadence Allegro 16.3-S048*
G04 Origin Date:  Tue Nov 26 10:18:24 2013*
G04 *
G04 Layer:  DRAWING FORMAT/TITLE_DATA_GND2*
G04 Layer:  VIA CLASS/GND2*
G04 Layer:  PIN/GND2*
G04 Layer:  MANUFACTURING/PHOTOPLOT_OUTLINE*
G04 Layer:  ETCH/GND2*
G04 Layer:  DRAWING FORMAT/TITLE_BLOCK*
G04 *
G04 Offset:    (0.00 0.00)*
G04 Mirror:    No*
G04 Mode:      Negative*
G04 Rotation:  0*
G04 FullContactRelief:  No*
G04 UndefLineWidth:     6.00*
G04 ================== end FILE IDENTIFICATION RECORD ====================*
%FSLAX25Y25*MOIN*%
%IR0*IPPOS*OFA0.00000B0.00000*MIA0B0*SFA1.00000B1.00000*%
%ADD10C,.03*%
%ADD17C,.06*%
%ADD46C,.061*%
%AMMACRO37*
4,1,36,0.0,.01,
-.001736,.009848,
-.00342,.009397,
-.005,.00866,
-.006428,.00766,
-.00766,.006428,
-.00866,.005,
-.009397,.00342,
-.009848,.001736,
-.01,0.0,
-.009848,-.001736,
-.009397,-.00342,
-.00866,-.005,
-.00766,-.006428,
-.006428,-.00766,
-.005,-.00866,
-.00342,-.009397,
-.001736,-.009848,
0.0,-.01,
.001736,-.009848,
.00342,-.009397,
.005,-.00866,
.006428,-.00766,
.00766,-.006428,
.00866,-.005,
.009397,-.00342,
.009848,-.001736,
.01,0.0,
.009848,.001736,
.009397,.00342,
.00866,.005,
.00766,.006428,
.006428,.00766,
.005,.00866,
.00342,.009397,
.001736,.009848,
0.0,.01,
0.0*
%
%ADD37MACRO37*%
%ADD34C,.026*%
%ADD21C,.053*%
%ADD11C,.08*%
%ADD36C,.072*%
%AMMACRO53*
4,1,16,.04526,.02758,
.049362,.019302,
.051963,.010437,
.052986,.001255,
.052399,-.007965,
.05022,-.016943,
.046515,-.025406,
.04526,-.02758,
.05033,-.03266,
.055237,-.023424,
.058465,-.013476,
.059917,-.003119,
.059548,.007332,
.057371,.017562,
.053449,.027257,
.05033,.03266,
.04526,.02758,
90.*
4,1,16,.02758,-.04526,
.019302,-.049362,
.010437,-.051963,
.001255,-.052986,
-.007965,-.052399,
-.016943,-.05022,
-.025406,-.046515,
-.02758,-.04526,
-.03266,-.05033,
-.023424,-.055237,
-.013476,-.058465,
-.003119,-.059917,
.007332,-.059548,
.017562,-.057371,
.027257,-.053449,
.03266,-.05033,
.02758,-.04526,
90.*
4,1,16,-.04526,-.02758,
-.049362,-.019302,
-.051963,-.010437,
-.052986,-.001255,
-.052399,.007965,
-.05022,.016943,
-.046515,.025406,
-.04526,.02758,
-.05033,.03266,
-.055237,.023424,
-.058465,.013476,
-.059917,.003119,
-.059548,-.007332,
-.057371,-.017562,
-.053449,-.027257,
-.05033,-.03266,
-.04526,-.02758,
90.*
4,1,16,-.02758,.04526,
-.019302,.049362,
-.010437,.051963,
-.001255,.052986,
.007965,.052399,
.016943,.05022,
.025406,.046515,
.02758,.04526,
.03266,.05033,
.023424,.055237,
.013476,.058465,
.003119,.059917,
-.007332,.059548,
-.017562,.057371,
-.027257,.053449,
-.03266,.05033,
-.02758,.04526,
90.*
%
%ADD53MACRO53*%
%ADD51C,.046*%
%ADD41C,.064*%
%ADD48C,.056*%
%ADD44C,.066*%
%ADD38C,.076*%
%AMMACRO32*
4,1,36,0.0,.004,
.000695,.003939,
.001368,.003759,
.002,.003464,
.002571,.003064,
.003064,.002571,
.003464,.002,
.003759,.001368,
.003939,.000695,
.004,0.0,
.003939,-.000695,
.003759,-.001368,
.003464,-.002,
.003064,-.002571,
.002571,-.003064,
.002,-.003464,
.001368,-.003759,
.000695,-.003939,
0.0,-.004,
-.000695,-.003939,
-.001368,-.003759,
-.002,-.003464,
-.002571,-.003064,
-.003064,-.002571,
-.003464,-.002,
-.003759,-.001368,
-.003939,-.000695,
-.004,0.0,
-.003939,.000695,
-.003759,.001368,
-.003464,.002,
-.003064,.002571,
-.002571,.003064,
-.002,.003464,
-.001368,.003759,
-.000695,.003939,
0.0,.004,
180.*
%
%ADD32MACRO32*%
%AMMACRO26*
4,1,36,0.0,.004,
.000695,.003939,
.001368,.003759,
.002,.003464,
.002571,.003064,
.003064,.002571,
.003464,.002,
.003759,.001368,
.003939,.000695,
.004,0.0,
.003939,-.000695,
.003759,-.001368,
.003464,-.002,
.003064,-.002571,
.002571,-.003064,
.002,-.003464,
.001368,-.003759,
.000695,-.003939,
0.0,-.004,
-.000695,-.003939,
-.001368,-.003759,
-.002,-.003464,
-.002571,-.003064,
-.003064,-.002571,
-.003464,-.002,
-.003759,-.001368,
-.003939,-.000695,
-.004,0.0,
-.003939,.000695,
-.003759,.001368,
-.003464,.002,
-.003064,.002571,
-.002571,.003064,
-.002,.003464,
-.001368,.003759,
-.000695,.003939,
0.0,.004,
270.*
%
%ADD26MACRO26*%
%ADD33C,.095*%
%ADD28C,.068*%
%AMMACRO22*
4,1,20,-.0075,-.07601,
-.01225,-.074283,
-.016628,-.071757,
-.020501,-.06851,
-.023751,-.064639,
-.026279,-.060263,
-.02801,-.055514,
-.028889,-.050536,
-.029,-.048,
-.029,-.0075,
-.022,-.0075,
-.022,-.048,
-.021666,-.05182,
-.020673,-.055523,
-.019053,-.058998,
-.016854,-.062139,
-.014142,-.064851,
-.011002,-.06705,
-.007526,-.06867,
-.0075,-.06868,
-.0075,-.07601,
180.*
4,1,20,.0075,-.07601,
.0075,-.06868,
.010977,-.067064,
.014121,-.064869,
.016836,-.062161,
.019039,-.059023,
.020664,-.05555,
.021661,-.051847,
.022,-.048028,
.022,-.048,
.022,-.0075,
.029,-.0075,
.029,-.048,
.028559,-.053035,
.027251,-.057917,
.025115,-.062498,
.022216,-.066638,
.018642,-.070212,
.014502,-.073111,
.009921,-.075247,
.0075,-.07601,
180.*
4,1,20,-.029,.0075,
-.029,.048,
-.028559,.053035,
-.027251,.057917,
-.025115,.062498,
-.022216,.066638,
-.018642,.070212,
-.014502,.073111,
-.009921,.075247,
-.0075,.07601,
-.0075,.06868,
-.010977,.067064,
-.014121,.064869,
-.016836,.062161,
-.019039,.059023,
-.020664,.05555,
-.021661,.051847,
-.022,.048028,
-.022,.048,
-.022,.0075,
-.029,.0075,
180.*
4,1,20,.022,.0075,
.022,.048,
.021666,.05182,
.020673,.055523,
.019053,.058998,
.016854,.062139,
.014142,.064851,
.011002,.06705,
.007526,.06867,
.0075,.06868,
.0075,.07601,
.01225,.074283,
.016628,.071757,
.020501,.06851,
.023751,.064639,
.026279,.060263,
.02801,.055514,
.028889,.050536,
.029,.048,
.029,.0075,
.022,.0075,
180.*
%
%ADD22MACRO22*%
%ADD19C,.077*%
%ADD23C,.089*%
%AMMACRO52*
4,1,16,.0711,.04282,
.077455,.029823,
.081457,.01592,
.082984,.001533,
.08199,-.0129,
.078504,-.026942,
.072633,-.040164,
.0711,-.04282,
.07619,-.04791,
.083352,-.033952,
.087981,-.018962,
.089937,-.003396,
.089161,.012273,
.085675,.027569,
.079586,.042027,
.07619,.04791,
.0711,.04282,
0.0*
4,1,16,.04282,-.0711,
.029823,-.077455,
.01592,-.081457,
.001533,-.082984,
-.0129,-.08199,
-.026942,-.078504,
-.040164,-.072633,
-.04282,-.0711,
-.04791,-.07619,
-.033952,-.083352,
-.018962,-.087981,
-.003396,-.089937,
.012273,-.089161,
.027569,-.085675,
.042027,-.079586,
.04791,-.07619,
.04282,-.0711,
0.0*
4,1,16,-.0711,-.04282,
-.077455,-.029823,
-.081457,-.01592,
-.082984,-.001533,
-.08199,.0129,
-.078504,.026942,
-.072633,.040164,
-.0711,.04282,
-.07619,.04791,
-.083352,.033952,
-.087981,.018962,
-.089937,.003396,
-.089161,-.012273,
-.085675,-.027569,
-.079586,-.042027,
-.07619,-.04791,
-.0711,-.04282,
0.0*
4,1,16,-.04282,.0711,
-.029823,.077455,
-.01592,.081457,
-.001533,.082984,
.0129,.08199,
.026942,.078504,
.040164,.072633,
.04282,.0711,
.04791,.07619,
.033952,.083352,
.018962,.087981,
.003396,.089937,
-.012273,.089161,
-.027569,.085675,
-.042027,.079586,
-.04791,.07619,
-.04282,.0711,
0.0*
%
%ADD52MACRO52*%
%AMMACRO40*
4,1,19,.08773,.07358,
.099174,.057228,
.107605,.039137,
.112766,.019857,
.114501,-.000026,
.112757,-.019909,
.107587,-.039186,
.099148,-.057273,
.08773,-.07358,
.09269,-.07855,
.104922,-.061261,
.113966,-.042111,
.119547,-.021681,
.121496,-.000593,
.119753,.020514,
.114371,.040997,
.105515,.060234,
.093452,.077642,
.09269,.07855,
.08773,.07358,
0.0*
4,1,19,.07358,-.08773,
.057228,-.099174,
.039137,-.107605,
.019857,-.112766,
-.000026,-.114501,
-.019909,-.112757,
-.039186,-.107587,
-.057273,-.099148,
-.07358,-.08773,
-.07855,-.09269,
-.061261,-.104922,
-.042111,-.113966,
-.021681,-.119547,
-.000593,-.121496,
.020514,-.119753,
.040997,-.114371,
.060234,-.105515,
.077642,-.093452,
.07855,-.09269,
.07358,-.08773,
0.0*
4,1,19,-.08773,-.07358,
-.099174,-.057228,
-.107605,-.039137,
-.112766,-.019857,
-.114501,.000026,
-.112757,.019909,
-.107587,.039186,
-.099148,.057273,
-.08773,.07358,
-.09269,.07855,
-.104922,.061261,
-.113966,.042111,
-.119547,.021681,
-.121496,.000593,
-.119753,-.020514,
-.114371,-.040997,
-.105515,-.060234,
-.093452,-.077642,
-.09269,-.07855,
-.08773,-.07358,
0.0*
4,1,19,-.07358,.08773,
-.057228,.099174,
-.039137,.107605,
-.019857,.112766,
.000026,.114501,
.019909,.112757,
.039186,.107587,
.057273,.099148,
.07358,.08773,
.07855,.09269,
.061261,.104922,
.042111,.113966,
.021681,.119547,
.000593,.121496,
-.020514,.119753,
-.040997,.114371,
-.060234,.105515,
-.077642,.093452,
-.07855,.09269,
-.07358,.08773,
0.0*
%
%ADD40MACRO40*%
%AMMACRO54*
4,1,15,.02438,.01377,
.026401,.009327,
.027619,.004601,
.027999,-.000265,
.027527,-.005123,
.02622,-.009825,
.02438,-.01377,
.02948,-.01887,
.032309,-.013464,
.034156,-.007649,
.034965,-.001602,
.034712,.004494,
.033405,.010454,
.031082,.016095,
.02948,.01887,
.02438,.01377,
90.*
4,1,15,.01377,-.02438,
.009327,-.026401,
.004601,-.027619,
-.000265,-.027999,
-.005123,-.027527,
-.009825,-.02622,
-.01377,-.02438,
-.01887,-.02948,
-.013464,-.032309,
-.007649,-.034156,
-.001602,-.034965,
.004494,-.034712,
.010454,-.033405,
.016095,-.031082,
.01887,-.02948,
.01377,-.02438,
90.*
4,1,15,-.02438,-.01377,
-.026401,-.009327,
-.027619,-.004601,
-.027999,.000265,
-.027527,.005123,
-.02622,.009825,
-.02438,.01377,
-.02948,.01887,
-.032309,.013464,
-.034156,.007649,
-.034965,.001602,
-.034712,-.004494,
-.033405,-.010454,
-.031082,-.016095,
-.02948,-.01887,
-.02438,-.01377,
90.*
4,1,15,-.01377,.02438,
-.009327,.026401,
-.004601,.027619,
.000265,.027999,
.005123,.027527,
.009825,.02622,
.01377,.02438,
.01887,.02948,
.013464,.032309,
.007649,.034156,
.001602,.034965,
-.004494,.034712,
-.010454,.033405,
-.016095,.031082,
-.01887,.02948,
-.01377,.02438,
90.*
%
%ADD54MACRO54*%
%AMMACRO30*
4,1,16,.06818,.0399,
.074073,.027454,
.077715,.014175,
.078996,.000464,
.077876,-.01326,
.07439,-.026582,
.068644,-.039096,
.06818,-.0399,
.07329,-.045,
.079991,-.03159,
.084261,-.01722,
.085971,-.002326,
.085069,.012638,
.081582,.027218,
.075616,.040971,
.07329,.045,
.06818,.0399,
0.0*
4,1,16,.0399,-.06818,
.027454,-.074073,
.014175,-.077715,
.000464,-.078996,
-.01326,-.077876,
-.026582,-.07439,
-.039096,-.068644,
-.0399,-.06818,
-.045,-.07329,
-.03159,-.079991,
-.01722,-.084261,
-.002326,-.085971,
.012638,-.085069,
.027218,-.081582,
.040971,-.075616,
.045,-.07329,
.0399,-.06818,
0.0*
4,1,16,-.06818,-.0399,
-.074073,-.027454,
-.077715,-.014175,
-.078996,-.000464,
-.077876,.01326,
-.07439,.026582,
-.068644,.039096,
-.06818,.0399,
-.07329,.045,
-.079991,.03159,
-.084261,.01722,
-.085971,.002326,
-.085069,-.012638,
-.081582,-.027218,
-.075616,-.040971,
-.07329,-.045,
-.06818,-.0399,
0.0*
4,1,16,-.0399,.06818,
-.027454,.074073,
-.014175,.077715,
-.000464,.078996,
.01326,.077876,
.026582,.07439,
.039096,.068644,
.0399,.06818,
.045,.07329,
.03159,.079991,
.01722,.084261,
.002326,.085971,
-.012638,.085069,
-.027218,.081582,
-.040971,.075616,
-.045,.07329,
-.0399,.06818,
0.0*
%
%ADD30MACRO30*%
%AMMACRO47*
4,1,15,.02291,.0123,
.024698,.008135,
.025735,.003723,
.025991,-.000803,
.025456,-.005304,
.024149,-.009644,
.02291,-.0123,
.02803,-.01742,
.030629,-.012288,
.032298,-.006783,
.032985,-.001071,
.03267,.004673,
.031362,.010275,
.029101,.015565,
.02803,.01742,
.02291,.0123,
90.*
4,1,15,.0123,-.02291,
.008135,-.024698,
.003723,-.025735,
-.000803,-.025991,
-.005304,-.025456,
-.009644,-.024149,
-.0123,-.02291,
-.01742,-.02803,
-.012288,-.030629,
-.006783,-.032298,
-.001071,-.032985,
.004673,-.03267,
.010275,-.031362,
.015565,-.029101,
.01742,-.02803,
.0123,-.02291,
90.*
4,1,15,-.02291,-.0123,
-.024698,-.008135,
-.025735,-.003723,
-.025991,.000803,
-.025456,.005304,
-.024149,.009644,
-.02291,.0123,
-.02803,.01742,
-.030629,.012288,
-.032298,.006783,
-.032985,.001071,
-.03267,-.004673,
-.031362,-.010275,
-.029101,-.015565,
-.02803,-.01742,
-.02291,-.0123,
90.*
4,1,15,-.0123,.02291,
-.008135,.024698,
-.003723,.025735,
.000803,.025991,
.005304,.025456,
.009644,.024149,
.0123,.02291,
.01742,.02803,
.012288,.030629,
.006783,.032298,
.001071,.032985,
-.004673,.03267,
-.010275,.031362,
-.015565,.029101,
-.01742,.02803,
-.0123,.02291,
90.*
%
%ADD47MACRO47*%
%AMMACRO27*
4,1,15,.02438,.01377,
.026401,.009327,
.027619,.004601,
.027999,-.000265,
.027527,-.005123,
.02622,-.009825,
.02438,-.01377,
.02948,-.01887,
.032309,-.013464,
.034156,-.007649,
.034965,-.001602,
.034712,.004494,
.033405,.010454,
.031082,.016095,
.02948,.01887,
.02438,.01377,
0.0*
4,1,15,.01377,-.02438,
.009327,-.026401,
.004601,-.027619,
-.000265,-.027999,
-.005123,-.027527,
-.009825,-.02622,
-.01377,-.02438,
-.01887,-.02948,
-.013464,-.032309,
-.007649,-.034156,
-.001602,-.034965,
.004494,-.034712,
.010454,-.033405,
.016095,-.031082,
.01887,-.02948,
.01377,-.02438,
0.0*
4,1,15,-.02438,-.01377,
-.026401,-.009327,
-.027619,-.004601,
-.027999,.000265,
-.027527,.005123,
-.02622,.009825,
-.02438,.01377,
-.02948,.01887,
-.032309,.013464,
-.034156,.007649,
-.034965,.001602,
-.034712,-.004494,
-.033405,-.010454,
-.031082,-.016095,
-.02948,-.01887,
-.02438,-.01377,
0.0*
4,1,15,-.01377,.02438,
-.009327,.026401,
-.004601,.027619,
.000265,.027999,
.005123,.027527,
.009825,.02622,
.01377,.02438,
.01887,.02948,
.013464,.032309,
.007649,.034156,
.001602,.034965,
-.004494,.034712,
-.010454,.033405,
-.016095,.031082,
-.01887,.02948,
-.01377,.02438,
0.0*
%
%ADD27MACRO27*%
%AMMACRO20*
4,1,15,.0218,.01119,
.023412,.007234,
.024313,.003059,
.024474,-.001209,
.023893,-.005441,
.022585,-.009507,
.0218,-.01119,
.02694,-.01633,
.029366,-.011404,
.030901,-.006131,
.031496,-.000672,
.031134,.004807,
.029826,.010141,
.027612,.015166,
.02694,.01633,
.0218,.01119,
90.*
4,1,15,.01119,-.0218,
.007234,-.023412,
.003059,-.024313,
-.001209,-.024474,
-.005441,-.023893,
-.009507,-.022585,
-.01119,-.0218,
-.01633,-.02694,
-.011404,-.029366,
-.006131,-.030901,
-.000672,-.031496,
.004807,-.031134,
.010141,-.029826,
.015166,-.027612,
.01633,-.02694,
.01119,-.0218,
90.*
4,1,15,-.0218,-.01119,
-.023412,-.007234,
-.024313,-.003059,
-.024474,.001209,
-.023893,.005441,
-.022585,.009507,
-.0218,.01119,
-.02694,.01633,
-.029366,.011404,
-.030901,.006131,
-.031496,.000672,
-.031134,-.004807,
-.029826,-.010141,
-.027612,-.015166,
-.02694,-.01633,
-.0218,-.01119,
90.*
4,1,15,-.01119,.0218,
-.007234,.023412,
-.003059,.024313,
.001209,.024474,
.005441,.023893,
.009507,.022585,
.01119,.0218,
.01633,.02694,
.011404,.029366,
.006131,.030901,
.000672,.031496,
-.004807,.031134,
-.010141,.029826,
-.015166,.027612,
-.01633,.02694,
-.01119,.0218,
90.*
%
%ADD20MACRO20*%
%AMMACRO29*
4,1,16,.0273,.01669,
.029783,.011696,
.031362,.006346,
.031987,.000804,
.031641,-.004763,
.030333,-.010185,
.028104,-.015297,
.0273,-.01669,
.03237,-.02176,
.035657,-.015808,
.03786,-.009377,
.038913,-.00266,
.038784,.004138,
.037476,.01081,
.03503,.017153,
.03237,.02176,
.0273,.01669,
0.0*
4,1,16,.01669,-.0273,
.011696,-.029783,
.006346,-.031362,
.000804,-.031987,
-.004763,-.031641,
-.010185,-.030333,
-.015297,-.028104,
-.01669,-.0273,
-.02176,-.03237,
-.015808,-.035657,
-.009377,-.03786,
-.00266,-.038913,
.004138,-.038784,
.01081,-.037476,
.017153,-.03503,
.02176,-.03237,
.01669,-.0273,
0.0*
4,1,16,-.0273,-.01669,
-.029783,-.011696,
-.031362,-.006346,
-.031987,-.000804,
-.031641,.004763,
-.030333,.010185,
-.028104,.015297,
-.0273,.01669,
-.03237,.02176,
-.035657,.015808,
-.03786,.009377,
-.038913,.00266,
-.038784,-.004138,
-.037476,-.01081,
-.03503,-.017153,
-.03237,-.02176,
-.0273,-.01669,
0.0*
4,1,16,-.01669,.0273,
-.011696,.029783,
-.006346,.031362,
-.000804,.031987,
.004763,.031641,
.010185,.030333,
.015297,.028104,
.01669,.0273,
.02176,.03237,
.015808,.035657,
.009377,.03786,
.00266,.038913,
-.004138,.038784,
-.01081,.037476,
-.017153,.03503,
-.02176,.03237,
-.01669,.0273,
0.0*
%
%ADD29MACRO29*%
%ADD18C,.15*%
%ADD31C,.148*%
%ADD39C,.188*%
%AMMACRO25*
4,1,36,0.0,.004,
.000695,.003939,
.001368,.003759,
.002,.003464,
.002571,.003064,
.003064,.002571,
.003464,.002,
.003759,.001368,
.003939,.000695,
.004,0.0,
.003939,-.000695,
.003759,-.001368,
.003464,-.002,
.003064,-.002571,
.002571,-.003064,
.002,-.003464,
.001368,-.003759,
.000695,-.003939,
0.0,-.004,
-.000695,-.003939,
-.001368,-.003759,
-.002,-.003464,
-.002571,-.003064,
-.003064,-.002571,
-.003464,-.002,
-.003759,-.001368,
-.003939,-.000695,
-.004,0.0,
-.003939,.000695,
-.003759,.001368,
-.003464,.002,
-.003064,.002571,
-.002571,.003064,
-.002,.003464,
-.001368,.003759,
-.000695,.003939,
0.0,.004,
90.*
%
%ADD25MACRO25*%
%AMMACRO14*
4,1,36,0.0,.004,
.000695,.003939,
.001368,.003759,
.002,.003464,
.002571,.003064,
.003064,.002571,
.003464,.002,
.003759,.001368,
.003939,.000695,
.004,0.0,
.003939,-.000695,
.003759,-.001368,
.003464,-.002,
.003064,-.002571,
.002571,-.003064,
.002,-.003464,
.001368,-.003759,
.000695,-.003939,
0.0,-.004,
-.000695,-.003939,
-.001368,-.003759,
-.002,-.003464,
-.002571,-.003064,
-.003064,-.002571,
-.003464,-.002,
-.003759,-.001368,
-.003939,-.000695,
-.004,0.0,
-.003939,.000695,
-.003759,.001368,
-.003464,.002,
-.003064,.002571,
-.002571,.003064,
-.002,.003464,
-.001368,.003759,
-.000695,.003939,
0.0,.004,
0.0*
%
%ADD14MACRO14*%
%AMMACRO35*
4,1,36,0.0,.004,
.000695,.003939,
.001368,.003759,
.002,.003464,
.002571,.003064,
.003064,.002571,
.003464,.002,
.003759,.001368,
.003939,.000695,
.004,0.0,
.003939,-.000695,
.003759,-.001368,
.003464,-.002,
.003064,-.002571,
.002571,-.003064,
.002,-.003464,
.001368,-.003759,
.000695,-.003939,
0.0,-.004,
-.000695,-.003939,
-.001368,-.003759,
-.002,-.003464,
-.002571,-.003064,
-.003064,-.002571,
-.003464,-.002,
-.003759,-.001368,
-.003939,-.000695,
-.004,0.0,
-.003939,.000695,
-.003759,.001368,
-.003464,.002,
-.003064,.002571,
-.002571,.003064,
-.002,.003464,
-.001368,.003759,
-.000695,.003939,
0.0,.004,
.001*
%
%ADD35MACRO35*%
%AMMACRO50*
4,1,13,.01917,.00857,
.020367,.005111,
.020945,.001497,
.020887,-.002163,
.020194,-.005757,
.01917,-.00857,
.02438,-.01377,
.026401,-.009327,
.027619,-.004601,
.027999,.000265,
.027527,.005123,
.02622,.009825,
.02438,.01377,
.01917,.00857,
270.*
4,1,13,.00857,-.01917,
.005111,-.020367,
.001497,-.020945,
-.002163,-.020887,
-.005757,-.020194,
-.00857,-.01917,
-.01377,-.02438,
-.009327,-.026401,
-.004601,-.027619,
.000265,-.027999,
.005123,-.027527,
.009825,-.02622,
.01377,-.02438,
.00857,-.01917,
270.*
4,1,13,-.01917,-.00857,
-.020367,-.005111,
-.020945,-.001497,
-.020887,.002163,
-.020194,.005757,
-.01917,.00857,
-.02438,.01377,
-.026401,.009327,
-.027619,.004601,
-.027999,-.000265,
-.027527,-.005123,
-.02622,-.009825,
-.02438,-.01377,
-.01917,-.00857,
270.*
4,1,13,-.00857,.01917,
-.005111,.020367,
-.001497,.020945,
.002163,.020887,
.005757,.020194,
.00857,.01917,
.01377,.02438,
.009327,.026401,
.004601,.027619,
-.000265,.027999,
-.005123,.027527,
-.009825,.02622,
-.01377,.02438,
-.00857,.01917,
270.*
%
%ADD50MACRO50*%
%AMMACRO42*
4,1,15,.02438,.01377,
.026401,.009327,
.027619,.004601,
.027999,-.000265,
.027527,-.005123,
.02622,-.009825,
.02438,-.01377,
.02948,-.01887,
.032309,-.013464,
.034156,-.007649,
.034965,-.001602,
.034712,.004494,
.033405,.010454,
.031082,.016095,
.02948,.01887,
.02438,.01377,
270.*
4,1,15,.01377,-.02438,
.009327,-.026401,
.004601,-.027619,
-.000265,-.027999,
-.005123,-.027527,
-.009825,-.02622,
-.01377,-.02438,
-.01887,-.02948,
-.013464,-.032309,
-.007649,-.034156,
-.001602,-.034965,
.004494,-.034712,
.010454,-.033405,
.016095,-.031082,
.01887,-.02948,
.01377,-.02438,
270.*
4,1,15,-.02438,-.01377,
-.026401,-.009327,
-.027619,-.004601,
-.027999,.000265,
-.027527,.005123,
-.02622,.009825,
-.02438,.01377,
-.02948,.01887,
-.032309,.013464,
-.034156,.007649,
-.034965,.001602,
-.034712,-.004494,
-.033405,-.010454,
-.031082,-.016095,
-.02948,-.01887,
-.02438,-.01377,
270.*
4,1,15,-.01377,.02438,
-.009327,.026401,
-.004601,.027619,
.000265,.027999,
.005123,.027527,
.009825,.02622,
.01377,.02438,
.01887,.02948,
.013464,.032309,
.007649,.034156,
.001602,.034965,
-.004494,.034712,
-.010454,.033405,
-.016095,.031082,
-.01887,.02948,
-.01377,.02438,
270.*
%
%ADD42MACRO42*%
%AMMACRO16*
4,1,15,.02438,.01377,
.026401,.009327,
.027619,.004601,
.027999,-.000265,
.027527,-.005123,
.02622,-.009825,
.02438,-.01377,
.02948,-.01887,
.032309,-.013464,
.034156,-.007649,
.034965,-.001602,
.034712,.004494,
.033405,.010454,
.031082,.016095,
.02948,.01887,
.02438,.01377,
180.*
4,1,15,.01377,-.02438,
.009327,-.026401,
.004601,-.027619,
-.000265,-.027999,
-.005123,-.027527,
-.009825,-.02622,
-.01377,-.02438,
-.01887,-.02948,
-.013464,-.032309,
-.007649,-.034156,
-.001602,-.034965,
.004494,-.034712,
.010454,-.033405,
.016095,-.031082,
.01887,-.02948,
.01377,-.02438,
180.*
4,1,15,-.02438,-.01377,
-.026401,-.009327,
-.027619,-.004601,
-.027999,.000265,
-.027527,.005123,
-.02622,.009825,
-.02438,.01377,
-.02948,.01887,
-.032309,.013464,
-.034156,.007649,
-.034965,.001602,
-.034712,-.004494,
-.033405,-.010454,
-.031082,-.016095,
-.02948,-.01887,
-.02438,-.01377,
180.*
4,1,15,-.01377,.02438,
-.009327,.026401,
-.004601,.027619,
.000265,.027999,
.005123,.027527,
.009825,.02622,
.01377,.02438,
.01887,.02948,
.013464,.032309,
.007649,.034156,
.001602,.034965,
-.004494,.034712,
-.010454,.033405,
-.016095,.031082,
-.01887,.02948,
-.01377,.02438,
180.*
%
%ADD16MACRO16*%
%AMMACRO45*
4,1,15,.02475,.01414,
.026829,.009627,
.028094,.004822,
.028504,-.000129,
.028049,-.005077,
.026741,-.009871,
.02475,-.01414,
.02984,-.01923,
.032726,-.013756,
.034617,-.007864,
.035457,-.001734,
.03522,.00445,
.033912,.010498,
.031574,.016227,
.02984,.01923,
.02475,.01414,
180.*
4,1,15,.01414,-.02475,
.009627,-.026829,
.004822,-.028094,
-.000129,-.028504,
-.005077,-.028049,
-.009871,-.026741,
-.01414,-.02475,
-.01923,-.02984,
-.013756,-.032726,
-.007864,-.034617,
-.001734,-.035457,
.00445,-.03522,
.010498,-.033912,
.016227,-.031574,
.01923,-.02984,
.01414,-.02475,
180.*
4,1,15,-.02475,-.01414,
-.026829,-.009627,
-.028094,-.004822,
-.028504,.000129,
-.028049,.005077,
-.026741,.009871,
-.02475,.01414,
-.02984,.01923,
-.032726,.013756,
-.034617,.007864,
-.035457,.001734,
-.03522,-.00445,
-.033912,-.010498,
-.031574,-.016227,
-.02984,-.01923,
-.02475,-.01414,
180.*
4,1,15,-.01414,.02475,
-.009627,.026829,
-.004822,.028094,
.000129,.028504,
.005077,.028049,
.009871,.026741,
.01414,.02475,
.01923,.02984,
.013756,.032726,
.007864,.034617,
.001734,.035457,
-.00445,.03522,
-.010498,.033912,
-.016227,.031574,
-.01923,.02984,
-.01414,.02475,
180.*
%
%ADD45MACRO45*%
%AMMACRO43*
4,1,16,.02657,.01597,
.02894,.011114,
.03043,.005919,
.030995,.000545,
.030619,-.004845,
.029313,-.010088,
.027115,-.015025,
.02657,-.01597,
.03164,-.02104,
.034813,-.015226,
.036928,-.00895,
.037921,-.002401,
.037762,.00422,
.036455,.010713,
.034041,.016881,
.03164,.02104,
.02657,.01597,
270.*
4,1,16,.01597,-.02657,
.011114,-.02894,
.005919,-.03043,
.000545,-.030995,
-.004845,-.030619,
-.010088,-.029313,
-.015025,-.027115,
-.01597,-.02657,
-.02104,-.03164,
-.015226,-.034813,
-.00895,-.036928,
-.002401,-.037921,
.00422,-.037762,
.010713,-.036455,
.016881,-.034041,
.02104,-.03164,
.01597,-.02657,
270.*
4,1,16,-.02657,-.01597,
-.02894,-.011114,
-.03043,-.005919,
-.030995,-.000545,
-.030619,.004845,
-.029313,.010088,
-.027115,.015025,
-.02657,.01597,
-.03164,.02104,
-.034813,.015226,
-.036928,.00895,
-.037921,.002401,
-.037762,-.00422,
-.036455,-.010713,
-.034041,-.016881,
-.03164,-.02104,
-.02657,-.01597,
270.*
4,1,16,-.01597,.02657,
-.011114,.02894,
-.005919,.03043,
-.000545,.030995,
.004845,.030619,
.010088,.029313,
.015025,.027115,
.01597,.02657,
.02104,.03164,
.015226,.034813,
.00895,.036928,
.002401,.037921,
-.00422,.037762,
-.010713,.036455,
-.016881,.034041,
-.02104,.03164,
-.01597,.02657,
270.*
%
%ADD43MACRO43*%
%AMMACRO49*
4,1,16,.0302,.01959,
.033143,.014048,
.035079,.00808,
.035949,.001865,
.035727,-.004405,
.034419,-.010542,
.032065,-.016359,
.0302,-.01959,
.03524,-.02464,
.038983,-.018146,
.041542,-.011101,
.042839,-.003719,
.042834,.003777,
.041527,.011157,
.038959,.018199,
.03524,.02464,
.0302,.01959,
270.*
4,1,16,.01959,-.0302,
.014048,-.033143,
.00808,-.035079,
.001865,-.035949,
-.004405,-.035727,
-.010542,-.034419,
-.016359,-.032065,
-.01959,-.0302,
-.02464,-.03524,
-.018146,-.038983,
-.011101,-.041542,
-.003719,-.042839,
.003777,-.042834,
.011157,-.041527,
.018199,-.038959,
.02464,-.03524,
.01959,-.0302,
270.*
4,1,16,-.0302,-.01959,
-.033143,-.014048,
-.035079,-.00808,
-.035949,-.001865,
-.035727,.004405,
-.034419,.010542,
-.032065,.016359,
-.0302,.01959,
-.03524,.02464,
-.038983,.018146,
-.041542,.011101,
-.042839,.003719,
-.042834,-.003777,
-.041527,-.011157,
-.038959,-.018199,
-.03524,-.02464,
-.0302,-.01959,
270.*
4,1,16,-.01959,.0302,
-.014048,.033143,
-.00808,.035079,
-.001865,.035949,
.004405,.035727,
.010542,.034419,
.016359,.032065,
.01959,.0302,
.02464,.03524,
.018146,.038983,
.011101,.041542,
.003719,.042839,
-.003777,.042834,
-.011157,.041527,
-.018199,.038959,
-.02464,.03524,
-.01959,.0302,
270.*
%
%ADD49MACRO49*%
%AMMACRO24*
4,1,17,.03056,.01996,
.033562,.01435,
.035544,.008304,
.036446,.002006,
.03624,-.004353,
.034934,-.01058,
.032566,-.016486,
.03056,-.01996,
.0356,-.025,
.0394,-.018438,
.042004,-.011316,
.043331,-.003851,
.043341,.003732,
.042034,.011201,
.039451,.018331,
.035668,.024903,
.0356,.025,
.03056,.01996,
270.*
4,1,17,.01996,-.03056,
.01435,-.033562,
.008304,-.035544,
.002006,-.036446,
-.004353,-.03624,
-.01058,-.034934,
-.016486,-.032566,
-.01996,-.03056,
-.025,-.0356,
-.018438,-.0394,
-.011316,-.042004,
-.003851,-.043331,
.003732,-.043341,
.011201,-.042034,
.018331,-.039451,
.024903,-.035668,
.025,-.0356,
.01996,-.03056,
270.*
4,1,17,-.03056,-.01996,
-.033562,-.01435,
-.035544,-.008304,
-.036446,-.002006,
-.03624,.004353,
-.034934,.01058,
-.032566,.016486,
-.03056,.01996,
-.0356,.025,
-.0394,.018438,
-.042004,.011316,
-.043331,.003851,
-.043341,-.003732,
-.042034,-.011201,
-.039451,-.018331,
-.035668,-.024903,
-.0356,-.025,
-.03056,-.01996,
270.*
4,1,17,-.01996,.03056,
-.01435,.033562,
-.008304,.035544,
-.002006,.036446,
.004353,.03624,
.01058,.034934,
.016486,.032566,
.01996,.03056,
.025,.0356,
.018438,.0394,
.011316,.042004,
.003851,.043331,
-.003732,.043341,
-.011201,.042034,
-.018331,.039451,
-.024903,.035668,
-.025,.0356,
-.01996,.03056,
270.*
%
%ADD24MACRO24*%
%ADD55C,.006*%
%ADD56C,.07006*%
%ADD60C,.09107*%
%ADD59C,.0971*%
%ADD58C,.07807*%
%ADD57C,.07907*%
%ADD61C,.15206*%
%ADD62C,.15806*%
%ADD63C,.19786*%
G75*
%LPD*%
G75*
G36*
G01X-1043962Y-705877D02*
X2300638D01*
Y2342823D01*
X-1043962D01*
Y-705877D01*
G37*
%LPC*%
G75*
G36*
G01X-69803Y813780D02*
G02X-63929Y819654I5874J0D01*
G01X-10373D01*
G02X-9873Y819154I0J-500D01*
G01Y633398D01*
X-9874D01*
Y2500D01*
G02X-10374Y2000I-500J0D01*
G01X-63929D01*
G02X-69803Y7874I0J5874D01*
G01Y813780D01*
G37*
G36*
G01X25591Y119256D02*
G03X33500Y127165I0J7909D01*
G01Y272835D01*
G03X25591Y280744I-7909J0D01*
G01X5906D01*
G02X2004Y284646I0J3902D01*
G01Y650316D01*
X2000Y650312D01*
Y659188D01*
X2004D01*
Y664173D01*
G02X7874Y670043I5870J0D01*
G01X40787D01*
G03X50665Y679921I0J9878D01*
G01Y818635D01*
G02X50812Y818990I500J1D01*
G01X51474Y819648D01*
X326199D01*
X326825Y819026D01*
G02X326972Y818671I-353J-354D01*
G01Y792323D01*
G03X338461I5744J0D01*
G01Y818632D01*
G02X338608Y818987I500J1D01*
G01X339273Y819648D01*
X377776D01*
X378547Y818877D01*
Y741142D01*
G03X408933I15193J0D01*
G01Y818634D01*
G02X409080Y818989I500J1D01*
G01X409743Y819648D01*
X684469D01*
X684973Y819147D01*
X685240Y818880D01*
Y792323D01*
G03X696728I5744J0D01*
G01Y818629D01*
G02X696875Y818984I500J1D01*
G01X697543Y819648D01*
X736038D01*
X736668Y819022D01*
G02X736815Y818667I-353J-354D01*
G01Y679921D01*
G03X746693Y670043I9878J0D01*
G01X779528D01*
G02X785398Y664173I0J-5870D01*
G01Y297835D01*
G02X781496Y293933I-3902J0D01*
G01X780315D01*
G03X772405Y286024I0J-7910D01*
G01Y132480D01*
G03X780315Y124571I7910J1D01*
G01X781496D01*
G02X785398Y120669I0J-3902D01*
G01Y7874D01*
G02X779528Y2004I-5870J0D01*
G01X7874D01*
G02X2004Y7874I0J5870D01*
G01Y115354D01*
G02X5906Y119256I3902J0D01*
G01X25591D01*
G37*
%LPD*%
G75*
G36*
G01X636562Y200784D02*
Y194458D01*
X635625Y193521D01*
X634299D01*
X633362Y194458D01*
Y200784D01*
X634299Y201721D01*
X635625D01*
X636562Y200784D01*
G37*
G36*
G01X615052Y202078D02*
Y192609D01*
X613090Y190647D01*
X610314D01*
X608352Y192609D01*
Y202078D01*
X610314Y204040D01*
X613090D01*
X615052Y202078D01*
G37*
G36*
G01X626400Y185616D02*
Y179290D01*
X625463Y178353D01*
X624137D01*
X623200Y179290D01*
Y185616D01*
X624137Y186553D01*
X625463D01*
X626400Y185616D01*
G37*
G36*
G01X615052Y187078D02*
Y177609D01*
X613090Y175647D01*
X610314D01*
X608352Y177609D01*
Y187078D01*
X610314Y189040D01*
X613090D01*
X615052Y187078D01*
G37*
G36*
G01X612516Y69078D02*
G02X608614Y65176I-3902J0D01*
G02X604612Y69178I0J4002D01*
G02X612516I3952J0D01*
G01Y69078D01*
G37*
G36*
G01X587858D02*
G02X583956Y65176I-3902J0D01*
G02X579954Y69178I0J4002D01*
G02X587858I3952J0D01*
G01Y69078D01*
G37*
G36*
G01X397421Y38554D02*
G02X396249Y35852I-3703J1D01*
G01X395926D01*
G03X395426Y35352I0J-501D01*
G01Y35269D01*
G02X392030Y35258I-1709J3285D01*
G01Y35354D01*
G03X391530Y35854I-500J0D01*
G01X391184D01*
G02X391187Y41256I2534J2700D01*
G01X391532D01*
G03X392032Y41756I0J500D01*
G01Y41851D01*
G02X395426Y41839I1685J-3297D01*
G01Y41756D01*
G03X395926Y41256I500J1D01*
G01X396249D01*
G02X397421Y38554I-2531J-2703D01*
G37*
G36*
G01X358051D02*
G02X356879Y35852I-3703J1D01*
G01X356556D01*
G03X356056Y35352I1J-501D01*
G01Y35269D01*
G02X352660Y35258I-1709J3285D01*
G01Y35354D01*
G03X352160Y35854I-500J0D01*
G01X351814D01*
G02X351817Y41256I2534J2700D01*
G01X352162D01*
G03X352662Y41756I0J500D01*
G01Y41851D01*
G02X356056Y41839I1685J-3297D01*
G01Y41756D01*
G03X356556Y41256I501J1D01*
G01X356879D01*
G02X358051Y38554I-2531J-2703D01*
G37*
G54D56*
X-44872Y125213D03*
Y141213D03*
Y232533D03*
Y248533D03*
Y738493D03*
Y754493D03*
X-26872Y125213D03*
Y141213D03*
Y232533D03*
Y248533D03*
Y738493D03*
Y754493D03*
G54D60*
X43898Y168544D03*
Y231457D03*
G54D59*
X151969Y98622D03*
G54D58*
X414961D03*
G54D57*
X434102Y311875D03*
Y232640D03*
G54D61*
X25455Y303232D03*
Y356832D03*
G54D62*
X102362Y247244D03*
Y349606D03*
X354331Y247244D03*
Y349606D03*
G54D63*
X413386Y377165D03*
G54D10*
X-294532Y1044846D03*
X-281332D03*
X-287932D03*
X-267012Y1044916D03*
X-39858Y731383D03*
X-31858D03*
X4390Y533777D03*
X13170Y372673D03*
X18340Y366452D03*
X13120Y375871D03*
X16010Y369168D03*
X21530Y368991D03*
X14140Y391826D03*
X18210Y386530D03*
X13950Y388616D03*
X13390Y397543D03*
X14240Y394866D03*
X19450Y550297D03*
X20650Y546243D03*
X20350Y555807D03*
X18960Y572061D03*
X17876Y578422D03*
X16200Y566921D03*
X17020Y592934D03*
X13510Y591939D03*
X15850Y610980D03*
X14500Y601957D03*
X11980Y617956D03*
X15349Y614142D03*
X14550Y628297D03*
X13807Y634826D03*
X9300Y631472D03*
X9240Y638699D03*
X11680Y656335D03*
X9260Y658321D03*
X14000Y658369D03*
X14170Y653991D03*
X9360Y653943D03*
X23987Y12977D03*
X36848Y25198D03*
X28408Y26414D03*
X30274Y37714D03*
X36588Y32278D03*
X36567Y73145D03*
X39126Y84631D03*
X34008Y91017D03*
X36567Y107988D03*
X32260Y96899D03*
X38280Y362184D03*
X35750Y364593D03*
X33420Y367309D03*
X23860Y366275D03*
X34140Y540345D03*
X34240Y536966D03*
X33231Y556346D03*
X30672Y551245D03*
X23610Y568111D03*
X28112Y591718D03*
X28270Y602194D03*
X33140Y602232D03*
X28185Y612088D03*
X30744Y617898D03*
X24168Y655750D03*
X37920Y651828D03*
X49890Y30392D03*
X51580Y17595D03*
X42205Y21518D03*
X54800Y25547D03*
X50981Y58681D03*
X46981Y58690D03*
X44010Y55170D03*
X54981Y59420D03*
X49559Y50577D03*
X41685Y73110D03*
X54101Y74252D03*
X51340Y69181D03*
X46570Y73891D03*
X47510Y109421D03*
X40690Y359555D03*
X53340Y393132D03*
X49750Y387305D03*
X51720Y384808D03*
X50840Y395761D03*
X47820Y398827D03*
X51670Y462885D03*
X47590Y463876D03*
X49830Y465496D03*
X47200Y467262D03*
X49590Y469432D03*
X49185Y472713D03*
X53769Y513033D03*
X54988Y518683D03*
X54117Y529098D03*
X49857Y520516D03*
X50630Y529281D03*
X41957Y543321D03*
X50140Y550572D03*
X39540Y538464D03*
X50870Y564008D03*
X43467Y555938D03*
X53988Y568748D03*
X49680Y579709D03*
X49620Y574212D03*
X47557Y588971D03*
X44507Y594082D03*
X40908Y589691D03*
X39360Y604593D03*
X39370Y600956D03*
X42950Y612487D03*
X50270Y627793D03*
X48540Y624953D03*
X52230Y614907D03*
X51051Y619407D03*
X48060Y621229D03*
X47480Y616848D03*
X51038Y643928D03*
X46890Y633564D03*
X53751Y652029D03*
X44640Y651029D03*
X40980Y656396D03*
X49720Y668412D03*
X56610Y20553D03*
X60318Y65593D03*
X64190Y72841D03*
X61760Y107321D03*
X55230Y112521D03*
X63900Y112081D03*
X64309Y141882D03*
X67853Y180744D03*
X68690Y175589D03*
X68930Y197193D03*
X66570Y189983D03*
X68830Y215817D03*
X56287Y242872D03*
X63718Y239030D03*
X61945Y267579D03*
X66818Y297483D03*
X57994Y287655D03*
X58000Y412641D03*
X64568Y451029D03*
X67568D03*
X70568D03*
X61357Y483392D03*
Y480892D03*
Y477892D03*
X61188Y487117D03*
X56330Y497940D03*
X58830D03*
X61676Y502656D03*
Y500156D03*
X61188Y489617D03*
Y492117D03*
X55982Y494543D03*
X64480Y501596D03*
X62253Y522589D03*
X67369Y522993D03*
X70696Y527237D03*
X57710Y572918D03*
X57070Y580074D03*
X57440Y585607D03*
X68630Y599945D03*
X61205Y623870D03*
X63570Y613914D03*
X63610Y618917D03*
X61205Y628870D03*
X62160Y644091D03*
X59390Y642906D03*
X56240Y630081D03*
X59530Y631704D03*
X63650Y646957D03*
X61600Y653611D03*
X66880Y761625D03*
X59260Y779815D03*
X58840Y783097D03*
X62290Y779629D03*
X67660Y779452D03*
X62730Y782694D03*
X66860Y782716D03*
X60370Y776861D03*
X64790Y776777D03*
X56500Y789667D03*
X76880Y126528D03*
X76030Y156152D03*
X85010Y171679D03*
X71510Y164548D03*
X74470Y175666D03*
X82553Y185431D03*
X86172Y213852D03*
X75560Y218513D03*
X73870Y205758D03*
X83390Y235665D03*
X79142Y237920D03*
X86479Y249259D03*
X77239Y260814D03*
X81165Y257717D03*
X78373Y276029D03*
X78220Y281745D03*
X78207Y279092D03*
X72190Y297395D03*
X82560Y288099D03*
X82600Y285426D03*
X77368Y299206D03*
X74058Y389621D03*
X83084D03*
X73868Y397913D03*
X83245D03*
X80490Y420690D03*
Y423690D03*
X86050Y428718D03*
X80490Y426690D03*
X79900Y439193D03*
X86050Y425112D03*
Y437470D03*
Y434470D03*
X79900Y445193D03*
Y442193D03*
X85617Y451275D03*
X82617D03*
X86050Y443432D03*
Y446432D03*
X74291Y486665D03*
X83536Y498308D03*
X81174Y503587D03*
X85346Y512295D03*
X73057Y515286D03*
X72635Y508991D03*
X81635Y521104D03*
X82031Y523928D03*
X84990Y563286D03*
X82140Y560758D03*
X81980Y556851D03*
X81516Y577905D03*
X83030Y582656D03*
X85140Y585213D03*
X75380Y608914D03*
Y603914D03*
X102257Y167955D03*
X90905Y199733D03*
X101449Y194368D03*
X98700Y234650D03*
X96990Y223043D03*
X101020Y223348D03*
X88399Y244041D03*
X95951Y376661D03*
X90031Y421693D03*
X90238Y418623D03*
X88617Y451275D03*
X86695Y498180D03*
X87721Y505817D03*
X92422Y531081D03*
X95660Y531362D03*
X98803Y531597D03*
X97268Y537055D03*
X97366Y542897D03*
X88200Y568111D03*
X98370Y619252D03*
X94070Y618986D03*
Y613841D03*
X97790Y613797D03*
X96200Y616325D03*
X95350Y644088D03*
X95310Y647481D03*
X98480Y646217D03*
X98410Y648878D03*
X89810Y765905D03*
X97390Y766435D03*
X98590Y782494D03*
X97180Y786472D03*
X111220Y160923D03*
X106090Y167615D03*
X112530Y186363D03*
X106760Y175370D03*
X114920Y179082D03*
X108910Y193194D03*
X104550Y262359D03*
X104270Y265662D03*
X110230Y360735D03*
X103151Y373340D03*
X110230Y363235D03*
X117030Y389978D03*
X103750Y402740D03*
X103810Y405876D03*
X103870Y399604D03*
X108235Y401017D03*
X111120Y401084D03*
X115727Y405844D03*
X113412Y404826D03*
X113504Y407673D03*
X107531Y394023D03*
X115516Y485696D03*
X117026Y488316D03*
X108026Y492500D03*
X109972Y509321D03*
Y519508D03*
X106358Y785790D03*
X102421Y782191D03*
X110295Y785734D03*
Y782191D03*
X116370Y785941D03*
X104300Y773100D03*
X106650Y779581D03*
X102421Y785938D03*
X130195Y19162D03*
X131068Y76588D03*
X126220Y80364D03*
Y83291D03*
X125480Y91163D03*
X132400Y88153D03*
X129580Y86837D03*
X129780Y92580D03*
X124150Y94643D03*
X128330Y98360D03*
X129650Y250414D03*
Y255414D03*
X130324Y272096D03*
Y277096D03*
X123960Y283696D03*
X128960D03*
X125050Y384546D03*
X122120Y386736D03*
X126300Y390369D03*
X129028Y425593D03*
X126377Y466738D03*
X126260Y470267D03*
X127705Y489431D03*
X125105D03*
X119326Y489706D03*
X121968Y488481D03*
X118124Y510811D03*
X133138Y510114D03*
X121644Y509398D03*
X130596Y510042D03*
X124652Y509398D03*
X130703Y512549D03*
X130844Y515128D03*
X128087Y513874D03*
X124279Y523691D03*
X120300Y572512D03*
X133590Y588438D03*
X130790Y595613D03*
X132190Y662616D03*
X121070Y670509D03*
X132050Y671817D03*
X133607Y686699D03*
X130260Y679836D03*
X132438Y704733D03*
X133490Y695470D03*
X126220Y720949D03*
X132334Y732982D03*
X119900Y754021D03*
X125600Y759000D03*
X125960Y785699D03*
X120090Y780618D03*
X130850Y782456D03*
X118169Y783857D03*
X130660Y785601D03*
X127290Y781982D03*
X122720Y785051D03*
X141490Y19267D03*
X137872Y29551D03*
X147427Y30367D03*
X146380Y20345D03*
X139931Y40842D03*
X139932Y35310D03*
X135050Y53493D03*
X137540Y58255D03*
X143857Y51943D03*
X149025Y51720D03*
X135290Y87664D03*
X140350Y81347D03*
X144400Y244061D03*
Y247561D03*
X148330Y258806D03*
X145200Y276468D03*
X138930Y278965D03*
X148350Y281769D03*
X134540Y267786D03*
X137990Y296735D03*
X139950Y293835D03*
X149020Y303498D03*
X145720Y311336D03*
X146100Y323543D03*
X145580Y316836D03*
X137889Y403348D03*
X141800Y404481D03*
X141847Y401820D03*
X135088Y405060D03*
X135181Y402121D03*
X145295Y404388D03*
X145284Y401507D03*
X142239Y422346D03*
X139395Y425090D03*
X138437Y435930D03*
Y438430D03*
X147576Y445279D03*
Y447779D03*
Y450279D03*
X138437Y440930D03*
X135300Y468444D03*
X146240Y472111D03*
X139310Y478102D03*
X136470Y481994D03*
X149477Y532733D03*
X144120Y547577D03*
X146920Y547677D03*
X143252Y573105D03*
X145550Y588088D03*
X149050Y588044D03*
X141260Y588175D03*
X136420Y599352D03*
X148140Y660112D03*
X148487Y676041D03*
X148200Y669205D03*
X140110Y675907D03*
X139158Y686725D03*
X135280Y679212D03*
X138726Y696707D03*
X138198Y712628D03*
X144631Y735955D03*
X147290Y744113D03*
X145040Y740741D03*
X139600Y781281D03*
X135470Y781697D03*
X135610Y784521D03*
X139680Y784596D03*
X149450Y780429D03*
X146150Y783820D03*
X145570Y780580D03*
X157877Y30674D03*
X152810Y29921D03*
X158165Y21300D03*
X150592Y20974D03*
X156255Y45743D03*
X159861Y36134D03*
X160731Y41038D03*
X162350Y42984D03*
X157659Y47891D03*
X157010Y58963D03*
X164550Y61239D03*
X156440Y74863D03*
X151618Y83343D03*
X164280Y101810D03*
X164490Y127110D03*
X159190Y127781D03*
X152990Y248096D03*
X157690Y249918D03*
X154546Y256986D03*
X152634Y276809D03*
X149721Y292987D03*
X152733Y288517D03*
X158076Y290635D03*
X154581Y308767D03*
X151230Y330164D03*
X150918Y318134D03*
X150510Y336306D03*
X156448Y336629D03*
X162071Y336947D03*
X165290Y385948D03*
X151820Y385554D03*
X150902Y379714D03*
X160886Y380294D03*
X160710Y384044D03*
X162940Y406188D03*
X154370Y449930D03*
X151145Y469456D03*
X150547Y459363D03*
X163377Y484538D03*
X152554Y494027D03*
X158406Y500016D03*
X162335Y512456D03*
X159196Y515612D03*
X159179Y521893D03*
X154126Y524411D03*
X154475Y530422D03*
X159180Y528227D03*
X162335Y543954D03*
X159185Y537654D03*
X162336Y550253D03*
X164259Y557273D03*
X154140Y577815D03*
X161280Y581585D03*
X162786Y568599D03*
X156480Y583315D03*
X153527Y597138D03*
X160699Y587904D03*
X150380Y602885D03*
X153712Y610917D03*
X153330Y599935D03*
X153422Y603043D03*
X153955Y620760D03*
X157963Y633735D03*
X162668Y631897D03*
X162530Y643235D03*
Y636435D03*
X151915Y675068D03*
X155957Y674813D03*
X160112Y674990D03*
X165012Y675887D03*
X164812Y662579D03*
X151567Y687579D03*
X155650Y681515D03*
X161994Y678445D03*
X159590Y683050D03*
X157287Y678138D03*
X165167Y681311D03*
X152222Y678394D03*
X160101Y687962D03*
X163018Y684381D03*
X164092Y688014D03*
X150840Y682436D03*
X154970Y736966D03*
X161981Y730784D03*
X158881D03*
X162640Y743927D03*
X158970D03*
X154400Y744337D03*
X155230Y740259D03*
X163138Y778565D03*
X160480Y777583D03*
X155170Y780656D03*
X164630Y781222D03*
X153320Y783499D03*
X160320Y786346D03*
X149810Y783858D03*
X168961Y27073D03*
X165959Y27133D03*
X173110Y26877D03*
X180907Y27544D03*
X176090Y26906D03*
X180159Y40661D03*
X165336Y46126D03*
X168040Y61462D03*
X177733Y91967D03*
X167383Y93147D03*
X168850Y99251D03*
X169510Y106579D03*
X173900Y97662D03*
X177680Y101764D03*
X174710Y105699D03*
X177763Y121057D03*
X168170Y123367D03*
X173170D03*
X178040Y228978D03*
X167483Y239914D03*
X177891Y249324D03*
X175756Y257668D03*
X173263Y262589D03*
X176301Y262624D03*
X167322Y255855D03*
X167698Y260617D03*
X178929Y262244D03*
X175110Y260412D03*
X178025Y279018D03*
X174078Y271435D03*
X170829Y271452D03*
X178941Y270160D03*
X178810Y287263D03*
X174148Y289289D03*
X175921Y301920D03*
X178921D03*
X178660Y388418D03*
X171934Y386364D03*
X175155Y380727D03*
X180430Y392969D03*
X175663Y386424D03*
X176371Y404721D03*
X180440Y398056D03*
X172760Y406540D03*
X167527Y420268D03*
X179562Y424001D03*
X173381Y424005D03*
X170683Y436834D03*
X170361Y428595D03*
X177525Y451946D03*
X180125D03*
X178961Y448138D03*
X176220Y448247D03*
X171616Y467804D03*
X168370Y477790D03*
X169728Y487664D03*
X168189Y514331D03*
X178085Y512456D03*
X173252Y515693D03*
X165707Y506156D03*
X172087Y510536D03*
X169615Y519216D03*
X178094Y531365D03*
X166297Y532416D03*
X169491Y529702D03*
X166837Y523486D03*
X174395Y527975D03*
X171606Y527511D03*
X168243Y542706D03*
X174930Y547106D03*
X169157Y548676D03*
X173163Y551903D03*
X169444Y558757D03*
X167105Y552882D03*
X178083Y553402D03*
X172889Y562710D03*
X175330Y578535D03*
X166930Y578435D03*
X166786Y569056D03*
X175386Y569589D03*
X179740Y568951D03*
X172430Y584035D03*
X177830Y583535D03*
X166570Y583874D03*
X166605Y587860D03*
X178416Y587849D03*
X179120Y639615D03*
X169930Y635329D03*
X172510Y639771D03*
X167530Y631935D03*
X174479Y631986D03*
X167810Y668131D03*
X168645Y688064D03*
X165628Y691289D03*
X167315Y684943D03*
X178982Y688631D03*
X171180Y683815D03*
X169268Y705304D03*
X169396Y701006D03*
X169268Y697399D03*
X169619Y693335D03*
X180820Y717914D03*
X171154Y715673D03*
X169531Y710542D03*
X175463Y720245D03*
X165599Y730476D03*
X174954Y728404D03*
X177920Y739302D03*
X167568Y743335D03*
X177224Y777765D03*
X169350Y785470D03*
X172600Y780150D03*
X169860Y782086D03*
X167350Y778074D03*
X194825Y10196D03*
X194861Y12952D03*
X183407Y27544D03*
X188634Y27860D03*
X191596Y27620D03*
X184928Y91847D03*
X189928D03*
X196653Y91837D03*
X196493Y105637D03*
X183013Y98813D03*
X190100Y99701D03*
X188203Y104567D03*
X194463Y122631D03*
X184050Y230139D03*
X183550Y235060D03*
X188899Y240208D03*
X195126Y249955D03*
X184296Y241098D03*
X188899Y236808D03*
X181176Y257643D03*
X188658Y256870D03*
X184117Y264852D03*
X181602Y262656D03*
X186873Y263697D03*
X185798Y256760D03*
X186873Y260697D03*
X194693Y259197D03*
Y262197D03*
X188418Y278887D03*
X183440Y269816D03*
X194205Y271034D03*
X191860Y270148D03*
X183198Y278034D03*
X191054Y294424D03*
X183254Y295023D03*
X192298Y286183D03*
X181921Y301920D03*
X191949Y301987D03*
X188810Y301998D03*
X187907Y308784D03*
X186254Y310663D03*
X183254D03*
X186350Y317116D03*
X196476Y317042D03*
X183228Y317023D03*
X193957Y317064D03*
X191159Y317171D03*
X190557Y325701D03*
X192230Y337322D03*
X192040Y333606D03*
X195420Y372406D03*
X184927Y383876D03*
X192681Y377554D03*
X193590Y383383D03*
X185074Y380726D03*
X196273Y403152D03*
X182132Y418327D03*
X192527Y429049D03*
X189077Y438281D03*
X184523Y441915D03*
X181923Y445044D03*
Y442544D03*
X193500Y489796D03*
X181231Y512455D03*
X184843Y533995D03*
X188640Y530667D03*
X191457Y531553D03*
X193466Y546886D03*
X186841Y545372D03*
X181232Y553402D03*
X181491Y557436D03*
X193080Y581235D03*
X191500Y571956D03*
X182480Y566819D03*
X196740Y589735D03*
X181330Y587535D03*
X192130Y632235D03*
X184748Y639687D03*
X182480Y634585D03*
X191480Y639135D03*
X182353Y631612D03*
X196410Y650155D03*
X187410Y649715D03*
Y659705D03*
X191910Y650055D03*
X185993Y682670D03*
X191542Y691925D03*
X181744Y694829D03*
X181950Y698191D03*
X190375Y695624D03*
X188566Y722353D03*
X183566D03*
X193566Y722333D03*
X196079Y723943D03*
X191150Y724108D03*
X186164Y724134D03*
X192949Y771020D03*
X182500Y780786D03*
X189770Y778082D03*
X204785Y13762D03*
X204978Y10605D03*
X201849Y15292D03*
X198577Y15374D03*
X204003Y91247D03*
X200480Y97687D03*
X212423Y104957D03*
X208908Y96975D03*
X205903Y101477D03*
X199993Y103637D03*
X210623Y121267D03*
X205535Y234497D03*
Y228682D03*
X211935Y230585D03*
X198296Y232699D03*
X211935Y237385D03*
Y240785D03*
X205566Y243497D03*
X205271Y240209D03*
X198685Y237385D03*
Y244085D03*
X210305Y259330D03*
Y262289D03*
X201994Y261248D03*
X200977Y256305D03*
X202402Y263713D03*
X200469Y259139D03*
X201518Y265990D03*
X209449Y281098D03*
X210303Y268227D03*
X206299Y281098D03*
X210303Y271227D03*
X203149Y281098D03*
X201518Y268887D03*
X209449Y287398D03*
Y290548D03*
X203149Y287398D03*
X206299D03*
X196867Y294342D03*
X206299Y290548D03*
X206319Y296863D03*
X203149Y290548D03*
X206299Y293698D03*
X198880Y310245D03*
X196812Y308619D03*
X206299Y306298D03*
Y303148D03*
X209449Y312598D03*
X203166Y312577D03*
X202525Y299358D03*
X206299Y315748D03*
X203058Y315593D03*
X200211Y321446D03*
X200572Y323920D03*
X208000Y325200D03*
X208700Y328000D03*
X200590Y327615D03*
X197938Y376839D03*
X206973Y361900D03*
X205790Y387003D03*
X201267Y403294D03*
X210880Y402359D03*
X206380Y402201D03*
X204584Y462478D03*
X197161Y465628D03*
X200459Y487253D03*
X211609Y516553D03*
X205257Y528822D03*
X211287Y528547D03*
X212342Y536729D03*
X199539Y537112D03*
X204309Y539953D03*
X205286Y551130D03*
X202486D03*
X211240Y572893D03*
X210040Y576893D03*
X201510Y576885D03*
X197730Y572893D03*
X197709Y567464D03*
X209590Y580893D03*
X210790Y566926D03*
X209940Y584893D03*
X197230Y595335D03*
X198890Y584105D03*
X207178Y591595D03*
X196907Y605012D03*
X197030Y598535D03*
X204024Y604135D03*
Y609135D03*
X208904Y611515D03*
X200380Y629085D03*
X199786Y618893D03*
X202510Y624005D03*
X197230Y615435D03*
X197130Y626135D03*
X208904Y616515D03*
X197480Y639815D03*
X203065Y638700D03*
X205221Y630886D03*
X200910Y659735D03*
Y650155D03*
X205410Y650035D03*
X199510Y663158D03*
X205410Y661200D03*
X211560Y670575D03*
X202518Y673273D03*
X197889Y671226D03*
X210824Y692266D03*
X199590Y682868D03*
X197582Y703474D03*
X200692Y704081D03*
X199350Y692724D03*
X211236Y695586D03*
X197243Y697899D03*
X198566Y722353D03*
X209017Y722344D03*
X203611Y722303D03*
X205440Y712510D03*
X211897Y723870D03*
X201411Y708231D03*
X205883Y724373D03*
X200817Y724180D03*
X199760Y763929D03*
X202050Y784919D03*
X206210Y771577D03*
X212350Y773283D03*
X222290Y45504D03*
X226290D03*
X221310Y51103D03*
X225310D03*
X215773Y90147D03*
X222983Y91587D03*
X220200Y93561D03*
X226620Y89385D03*
X214320Y101978D03*
X220983Y106174D03*
X213908Y96975D03*
X219510Y101338D03*
X228138Y125802D03*
X226010Y233542D03*
X217135Y230585D03*
X226010Y240342D03*
X217135Y240785D03*
Y237385D03*
X227517Y244187D03*
X216512Y258490D03*
X225973Y262197D03*
X216109Y265139D03*
Y262139D03*
X218508Y256664D03*
X225973Y265197D03*
Y259197D03*
X218899Y281098D03*
X224357Y273228D03*
X216109Y271139D03*
X215749Y281098D03*
X213138Y274187D03*
X225160Y293676D03*
X225199Y290548D03*
Y284248D03*
X222049Y287398D03*
X212599D03*
X215749Y290548D03*
Y293698D03*
Y287398D03*
X225199Y306298D03*
Y312598D03*
X222049Y306298D03*
X218899D03*
X222049Y299998D03*
X212610Y306305D03*
X218899Y299998D03*
Y303148D03*
X218947Y312617D03*
X224949Y328707D03*
X225199Y315748D03*
X224585Y322992D03*
X224711Y325922D03*
X223166Y338842D03*
X222911Y333155D03*
X224996Y334617D03*
X223095Y336241D03*
X221280Y340579D03*
X222974Y356134D03*
X214657Y356205D03*
X214007Y362701D03*
X222225Y364031D03*
X227745Y368007D03*
X224108Y388029D03*
X214786Y388603D03*
X218090Y390891D03*
X216633Y384989D03*
X215120Y399654D03*
X214406Y395539D03*
X223085Y401702D03*
X213710Y402237D03*
X224730Y418003D03*
X221406Y436560D03*
X227816Y442675D03*
X218483Y442550D03*
X221858Y442300D03*
X225024Y442467D03*
X228242Y463681D03*
X223953Y463550D03*
X212809Y479053D03*
X215409Y479253D03*
X222419Y479933D03*
X218040Y473853D03*
X223786Y476638D03*
X226255Y472579D03*
X219309Y489353D03*
X222209D03*
X227284Y502591D03*
X224209Y491853D03*
X217609Y516353D03*
X219328Y528823D03*
X223376Y523322D03*
X215946Y544202D03*
X218950Y565589D03*
X227100Y580916D03*
X225100Y597453D03*
X219960Y596373D03*
Y601373D03*
X215604Y621977D03*
X228290Y629893D03*
X218308Y635939D03*
X225179Y642614D03*
X218240Y674433D03*
X225237Y671772D03*
X212635Y665604D03*
X224060Y690317D03*
X224336Y687758D03*
X223707Y695436D03*
X220580Y692876D03*
X223741Y700554D03*
X221340Y697995D03*
X217530Y715305D03*
X221320Y720698D03*
X213310Y719064D03*
X222710Y713706D03*
X216820Y723301D03*
X227650Y720791D03*
X224410Y719970D03*
X225940Y733671D03*
Y736437D03*
X218270Y785657D03*
X220960Y778561D03*
X226670Y773299D03*
X242290Y45504D03*
X230290D03*
X229310Y51103D03*
X233290Y51045D03*
X237310Y50983D03*
X241310D03*
X235113Y91307D03*
X231013Y91547D03*
X243373Y88767D03*
X239563Y92077D03*
X230643Y108497D03*
X234243Y100156D03*
X233083Y94817D03*
X237773Y103607D03*
X242913Y106157D03*
X233138Y125802D03*
X230749Y160807D03*
X230650Y164566D03*
X230890Y169424D03*
X231000Y173381D03*
X230100Y187389D03*
X230140Y197240D03*
X232948Y234047D03*
X236710Y244042D03*
X242460Y237591D03*
X237654Y249719D03*
X231710Y243642D03*
Y240242D03*
X241613Y262197D03*
X239569Y266639D03*
X241613Y259197D03*
X237594Y252754D03*
X241613Y265197D03*
X233793Y266697D03*
Y257697D03*
X233904Y252772D03*
X239569Y263639D03*
X233793Y263697D03*
X231749Y262139D03*
X233793Y260697D03*
X239569Y260639D03*
X231749Y259139D03*
X234649Y281098D03*
X237865Y281131D03*
X239569Y269639D03*
X232118Y271587D03*
X241613Y271197D03*
Y268197D03*
X228821Y274197D03*
X231648Y274243D03*
X231450Y290583D03*
X237760Y293692D03*
X237799Y287398D03*
X240949Y290548D03*
Y287398D03*
X231499Y284248D03*
Y296848D03*
Y293698D03*
X240949Y296848D03*
X231499Y299998D03*
X237799Y312598D03*
X231499D03*
X240949Y309448D03*
X237799Y303148D03*
X234649D03*
X237799Y306298D03*
X240925Y306257D03*
X240949Y299998D03*
Y303148D03*
X231567Y321742D03*
X232782Y327096D03*
X230725Y325649D03*
X238545Y327149D03*
X240374Y328960D03*
X240511Y325517D03*
X238548Y333149D03*
X230725Y334547D03*
X240598Y334642D03*
X240218Y338010D03*
X231144Y338225D03*
X238560Y336136D03*
X232769Y333207D03*
X232804Y336181D03*
X239290Y340428D03*
X228419Y356855D03*
X233635Y357082D03*
X230010Y373300D03*
X237578Y369584D03*
X233136Y367070D03*
X243078Y368384D03*
X231257Y362218D03*
X228729Y385227D03*
X241451Y392147D03*
X236412Y387722D03*
X231223Y391424D03*
X239546Y390528D03*
X239228Y393291D03*
X236430Y393470D03*
X232647Y396011D03*
X228906Y424560D03*
X228713Y416525D03*
Y419525D03*
X231870Y439511D03*
X228906Y433560D03*
Y427560D03*
Y436560D03*
X231885Y442252D03*
X235319Y464362D03*
X231461Y462591D03*
X243471Y460292D03*
X238430Y460338D03*
X233309Y472553D03*
X237609Y472453D03*
X241909Y472553D03*
X234209Y480953D03*
X228604Y479682D03*
X233626Y512040D03*
X236776Y534087D03*
X233626Y524639D03*
X236776Y540386D03*
X235307Y566357D03*
X243209Y574018D03*
X229269Y597682D03*
X242830Y597415D03*
X234370Y593242D03*
X242796Y589749D03*
X236780Y628738D03*
X229199Y642180D03*
X243693Y632254D03*
X238420Y642148D03*
X234500Y637685D03*
X243743Y636514D03*
X241670Y652558D03*
X233584Y652519D03*
X239168Y671672D03*
X237275Y679609D03*
X239084Y696252D03*
X233954Y697395D03*
X236120Y704173D03*
X242680Y712337D03*
X234960Y714064D03*
X239210Y720040D03*
X234910Y720816D03*
X234940Y733355D03*
X243940Y736412D03*
X239500Y733523D03*
X230440Y724242D03*
X234940Y736392D03*
X236180Y786517D03*
X242230Y774803D03*
X234011Y772902D03*
X250290Y45504D03*
X246290D03*
X258103Y53688D03*
X257500Y56117D03*
X245310Y50867D03*
X249300Y50862D03*
X253490Y53736D03*
X252683Y105867D03*
X253558Y95038D03*
X256133Y99347D03*
X248558Y95038D03*
X249453Y114307D03*
X255287Y226709D03*
X254221Y230582D03*
X256492Y222466D03*
X254181Y234521D03*
X257950Y236924D03*
X254418Y240407D03*
X247389Y259139D03*
X256553Y256881D03*
X249433Y263697D03*
Y260697D03*
X256916Y262609D03*
X247389Y262139D03*
X257253Y259197D03*
X259518Y252358D03*
X249433Y257697D03*
X246467Y255442D03*
X244099Y281098D03*
X254234Y281622D03*
X250399Y281098D03*
X247389Y268139D03*
X257253Y271197D03*
Y268197D03*
X244110Y290505D03*
X257447Y287117D03*
X244099Y287398D03*
X250399D03*
X253549Y290548D03*
X247249Y296848D03*
X244099D03*
X258380Y295984D03*
X254007Y306819D03*
X244118Y303187D03*
X257057Y309636D03*
X244099Y299998D03*
X247249Y306298D03*
X257418Y303533D03*
X258590Y311560D03*
X247290Y327694D03*
X254631Y324716D03*
X254998Y329779D03*
X256276Y322652D03*
X247789Y322910D03*
X254905Y327213D03*
X250401Y315713D03*
X253710Y315669D03*
X246685Y337357D03*
X255124Y335244D03*
X247025Y330512D03*
X251491Y357134D03*
X256588Y359005D03*
X244595Y363535D03*
X256532Y384895D03*
X247065Y385398D03*
X244546Y385315D03*
X253762Y385255D03*
X247797Y406029D03*
X250297D03*
X252797D03*
X245297D03*
X258798Y417594D03*
X254798Y417728D03*
X254813Y427018D03*
X252670Y443592D03*
X246465Y464893D03*
X251780Y460883D03*
X257568Y461513D03*
X255509Y472253D03*
X246109Y472465D03*
X251309Y472553D03*
X252036Y582131D03*
X245860Y575049D03*
X249909Y568653D03*
X259678Y581553D03*
X253187Y596382D03*
X249013Y628514D03*
X251803Y636704D03*
X254773Y644424D03*
X254303Y636744D03*
X256463Y639364D03*
X252173Y644344D03*
X249083Y636664D03*
X256513Y642494D03*
X246553Y636684D03*
X252486Y671772D03*
X244780Y682521D03*
X250795Y703150D03*
X251451Y697465D03*
X259170Y705138D03*
X258570Y722981D03*
X255310Y715915D03*
X248530Y721829D03*
X250630Y719457D03*
X248770Y724631D03*
X252940Y733567D03*
X256650Y778342D03*
X247900Y778823D03*
X252470Y785797D03*
X262955Y12663D03*
X266111Y29229D03*
X265789Y20990D03*
X268809Y16400D03*
X274990Y16396D03*
X272010Y40553D03*
X274510D03*
X274580Y74281D03*
X269920Y74318D03*
X272440Y76177D03*
X268080Y76416D03*
X272245Y89585D03*
X263703Y93847D03*
X271133Y92787D03*
X273973Y97645D03*
X262473Y106937D03*
X263683Y99902D03*
X268702Y107928D03*
X269010Y121648D03*
X264980Y121886D03*
X269192Y248209D03*
X272242Y244842D03*
X272620Y238653D03*
X260108Y240376D03*
X267118Y245587D03*
X271458Y241347D03*
X270260Y237037D03*
X266187Y249852D03*
X273521Y265849D03*
X260068Y262187D03*
X263268Y262370D03*
X263774Y256464D03*
X272464Y259964D03*
X269263Y252800D03*
X263029Y271139D03*
Y268139D03*
X273444Y270543D03*
X274944Y278363D03*
X270386Y280407D03*
X267386D03*
Y296047D03*
X261463Y296111D03*
X265825Y293987D03*
X268867Y293942D03*
X270444Y286183D03*
X265768Y287546D03*
X273444Y286183D03*
X273618Y295387D03*
X260045Y309615D03*
X268944Y309643D03*
X265944Y309640D03*
X261915Y302033D03*
X269380Y302736D03*
X264501Y303109D03*
X266939Y303281D03*
X274303Y303413D03*
X259820Y303800D03*
X267268Y311642D03*
X264287Y311687D03*
X270518Y311637D03*
X274832Y309687D03*
X265318Y326487D03*
X270525Y325754D03*
X262201Y328491D03*
X272967Y325842D03*
X275517D03*
X267030Y330147D03*
X262700Y325494D03*
X270485Y339030D03*
X264015Y336151D03*
X263173Y331794D03*
X267943Y339617D03*
X270293Y330540D03*
X272964Y330669D03*
X262379Y338103D03*
X262247Y334502D03*
X270071Y333021D03*
X272263Y334222D03*
X272352Y340900D03*
X269456Y355353D03*
X269886Y358753D03*
X260536Y374216D03*
X270293Y363972D03*
X273477Y385100D03*
X261663Y385193D03*
X267993Y390695D03*
X270796Y386643D03*
X266882Y388165D03*
X261539Y387755D03*
X264421Y384812D03*
X275497Y390758D03*
X263419Y393450D03*
X265162Y401391D03*
X272220Y401343D03*
X271720Y422587D03*
X265532Y422648D03*
X269630Y424884D03*
X274180Y424966D03*
X266822Y443297D03*
X275256Y445753D03*
X271035Y443051D03*
X273735Y443034D03*
X273509Y471649D03*
X263807Y461234D03*
X260609Y472453D03*
X264909Y472553D03*
X269109Y472353D03*
X275452Y483219D03*
X263924Y491754D03*
X269609Y576413D03*
X274309Y574653D03*
X261175Y569054D03*
X263792Y574203D03*
X268009Y570953D03*
X273480Y589201D03*
X269609Y588653D03*
X268717Y606015D03*
X261967Y608638D03*
Y605638D03*
X260064Y602993D03*
X261967Y614638D03*
X263467Y626638D03*
X269428Y622966D03*
X261967Y617638D03*
X263467Y623638D03*
X273938Y633084D03*
X273674Y640095D03*
X273548Y636471D03*
X266610Y654171D03*
X270040Y651241D03*
X269640Y655290D03*
X265913Y671772D03*
X261890Y664761D03*
X265550Y668415D03*
X274360Y673831D03*
X272460Y687889D03*
X267240Y682519D03*
X269420Y677062D03*
X272650Y693742D03*
X269410Y706003D03*
X267124Y707892D03*
X273510Y699749D03*
X266170Y694826D03*
X260680Y712988D03*
X271210Y718000D03*
X264600Y723086D03*
X270940Y722080D03*
X263430Y770417D03*
X264340Y778780D03*
X272175Y783074D03*
X278660Y10073D03*
X284505Y30676D03*
X287766Y21289D03*
X277472Y34959D03*
Y37459D03*
X280072Y34330D03*
X275766Y52772D03*
X275800Y50212D03*
X287270Y75018D03*
X283870Y74724D03*
X279100Y74447D03*
X289738Y76173D03*
X285543Y76867D03*
X281400Y75938D03*
X276969Y76247D03*
X276603Y92119D03*
X287423Y91857D03*
X281200Y98369D03*
X289720Y96094D03*
X278760Y101061D03*
X287599Y108831D03*
X278880Y108482D03*
X279161Y237817D03*
X276904Y252550D03*
X282166Y262922D03*
X281945Y260231D03*
X278811Y259135D03*
X279336Y264795D03*
X276444Y270543D03*
X282309Y270435D03*
X279444Y270543D03*
X277944Y278363D03*
X279386Y280407D03*
X276386D03*
X281767Y277742D03*
X290363Y286082D03*
X286132Y285953D03*
X281818Y290787D03*
X278918Y286887D03*
X276444Y286183D03*
X277020Y302298D03*
X282337Y308217D03*
X281859Y310862D03*
X277816Y309678D03*
X279754Y303269D03*
X276386Y311687D03*
X286071Y329184D03*
X278067Y325842D03*
X282167Y324242D03*
X288466Y325343D03*
X285704Y321809D03*
X277288Y334282D03*
X282234Y333792D03*
X285794Y339063D03*
X281205Y340997D03*
X279718Y333694D03*
X275602Y343811D03*
X289191Y341348D03*
X286020Y356454D03*
X277040Y376172D03*
X279863Y367513D03*
X286550Y374402D03*
X281450Y373151D03*
X288687Y385290D03*
X281864Y386178D03*
X284687Y386769D03*
X285390Y390550D03*
X288220Y389630D03*
X287067Y402358D03*
X280730Y393856D03*
X276400Y422341D03*
X280010Y422279D03*
X281190Y424966D03*
X278080Y424760D03*
X286210Y444926D03*
X289630Y444828D03*
X283212Y442286D03*
X286100Y442298D03*
X288742Y442090D03*
X287970Y446705D03*
X282000Y444966D03*
X279112Y444954D03*
X276626Y442913D03*
X279990Y442071D03*
X280210Y460762D03*
X287567Y470649D03*
Y467649D03*
X280380Y467284D03*
X278990Y464793D03*
X277470Y481197D03*
X280970D03*
X288009Y495653D03*
X284024Y502595D03*
X290323D03*
X280874Y556139D03*
X279658Y574443D03*
X285530Y573002D03*
X283650Y589044D03*
X278109Y589238D03*
X287997Y649064D03*
X280880Y650295D03*
X278699Y656491D03*
X279090Y668504D03*
X279785Y663876D03*
X289365Y665845D03*
Y673719D03*
X279843Y675688D03*
X278350Y687309D03*
X275710Y681593D03*
X289248Y680521D03*
X275560Y697804D03*
X279060Y693306D03*
X284760Y707022D03*
X286798Y704143D03*
X278370Y705093D03*
X277475Y695723D03*
X289060Y722193D03*
X281830Y722184D03*
X285130Y714433D03*
X275880Y722141D03*
X285880Y722268D03*
X289150Y718548D03*
X280210Y734805D03*
X288390Y734796D03*
X284020Y724956D03*
X284532Y747493D03*
X275627Y777692D03*
X281930Y773190D03*
X286722Y785929D03*
X292313Y76345D03*
X305880Y76361D03*
X299220Y76196D03*
X302953Y76167D03*
X295867Y76567D03*
X301870Y92072D03*
X296870D03*
X291927Y102991D03*
X293505Y94965D03*
X296927Y102991D03*
X303220Y98397D03*
X299590Y121289D03*
X299850Y124708D03*
X302930Y132994D03*
X296176Y249585D03*
X299776Y248010D03*
X301511Y262204D03*
X300477Y265010D03*
X296210Y253187D03*
X300310Y253842D03*
Y257242D03*
X292710Y266542D03*
X301473Y282650D03*
X297810Y280709D03*
X301723Y279150D03*
X301182Y291966D03*
X294382D03*
X305132Y286867D03*
X298332D03*
X301732D03*
X301795Y310398D03*
X296639Y308057D03*
X305250Y310342D03*
X300201Y300874D03*
X303197Y304297D03*
X297073Y329159D03*
X298452Y340487D03*
X305880Y339046D03*
X306820Y342146D03*
X299410Y331201D03*
X303759Y331478D03*
X305446Y359450D03*
X295527Y359812D03*
X303171Y374224D03*
X291686Y375177D03*
X295388Y375644D03*
X293290Y389737D03*
X291382Y385457D03*
X299533Y394056D03*
X291860Y442927D03*
X292170Y445986D03*
X300040Y459733D03*
X303631Y475607D03*
Y472607D03*
X297370Y498563D03*
X300209Y495853D03*
X305708Y503043D03*
X295047Y554565D03*
X304410Y572782D03*
X306229Y600263D03*
X301796Y603917D03*
X298303Y613184D03*
X302870Y633981D03*
X297162Y642065D03*
X293843Y642536D03*
X303110Y639381D03*
X301070Y655920D03*
X292850Y656359D03*
X304870Y655747D03*
X306294Y659156D03*
X297394Y657033D03*
X302772Y659604D03*
X301360Y652183D03*
X306294Y667156D03*
Y663156D03*
Y675156D03*
Y671156D03*
X300880Y664296D03*
X294120Y668391D03*
X295890Y662662D03*
X297770Y674720D03*
X305979Y691156D03*
X306145Y683156D03*
X305979Y687156D03*
X306294Y679156D03*
X292970Y682450D03*
X295950Y689520D03*
X293068Y677108D03*
X296858Y702544D03*
X297300Y697221D03*
X293286Y703504D03*
X305990Y697189D03*
X303681Y714421D03*
X305213Y720393D03*
X293300Y718944D03*
X296885Y718059D03*
X297223Y715523D03*
X291318Y713875D03*
X302810Y733807D03*
X298590Y733669D03*
X293480Y725080D03*
X295700Y733133D03*
X293440Y748380D03*
X291340Y771217D03*
X295100Y786269D03*
X299249Y771403D03*
X304740Y777277D03*
X317334Y10955D03*
X322640Y9774D03*
X317334Y28955D03*
X318910Y74595D03*
X314310Y74540D03*
X307740Y74263D03*
X309730Y76232D03*
X321283Y76327D03*
X316623Y76047D03*
X312402Y76587D03*
X315083Y90207D03*
X311553Y92347D03*
X310850Y99620D03*
X320740Y98599D03*
X312223Y96407D03*
X317970Y95961D03*
X313583Y122387D03*
X311290Y247249D03*
X312680Y258353D03*
X307204Y304212D03*
X310623Y313589D03*
X313123D03*
X320623D03*
X318123D03*
X315623D03*
X311740Y325839D03*
X313980Y335813D03*
X314550Y331564D03*
X318480Y335039D03*
X321130Y342418D03*
X309190Y336959D03*
X319807Y346376D03*
X321150Y357730D03*
X319288Y350376D03*
X307410Y348380D03*
X313222Y374229D03*
X322255Y371935D03*
X321297Y367739D03*
X319363Y372149D03*
X310484Y383312D03*
X321144Y399643D03*
X318644D03*
X316190Y413299D03*
X317140Y421775D03*
X321910Y410139D03*
X311610Y432528D03*
X313530Y436460D03*
X315940Y438104D03*
X319478Y429389D03*
X308220Y432552D03*
X322599Y432505D03*
X309440Y426404D03*
X318950Y432473D03*
X321357Y456709D03*
X307800Y467859D03*
X310380Y473942D03*
X321246Y472669D03*
X315980Y472128D03*
X307670Y473605D03*
X320080Y512736D03*
X318678Y540966D03*
X321828Y541682D03*
X313419Y594040D03*
X313227Y590232D03*
X310919Y594040D03*
X310627Y590232D03*
X315957Y594127D03*
X320094Y604114D03*
X320512Y613603D03*
X308741Y623871D03*
X311311Y618197D03*
X317492Y618193D03*
X314940Y642067D03*
X310453Y642451D03*
X320360Y642275D03*
X311382Y635432D03*
X316184Y662630D03*
X314614Y690767D03*
X316184Y687630D03*
X316165Y693404D03*
X313230Y702465D03*
X307113Y713003D03*
X321820Y712680D03*
X311990Y717601D03*
X319620Y716403D03*
X309531Y714298D03*
X312972Y712693D03*
X318090Y712846D03*
X307280Y733705D03*
X321930Y724895D03*
X314930Y724533D03*
X307146Y769416D03*
X315020Y780559D03*
X320657Y779595D03*
X320440Y771967D03*
X323334Y12377D03*
X323871Y25812D03*
Y16812D03*
Y19812D03*
Y28812D03*
X327117Y31840D03*
X323640Y74393D03*
X326140Y76196D03*
X335668Y92822D03*
X330668D03*
X325360Y92517D03*
X324070Y88861D03*
X325970Y98817D03*
X327430Y108208D03*
X327190Y103818D03*
X337630Y106304D03*
X334720Y102184D03*
X323032Y122237D03*
X331583Y128717D03*
X336495Y290569D03*
X328526Y308696D03*
X334478Y299604D03*
X323123Y313589D03*
X336720Y310846D03*
X337293Y316660D03*
X333540Y315590D03*
X333726Y353801D03*
X333440Y349221D03*
X327058Y358376D03*
X323040Y354485D03*
X336850Y380332D03*
X326282Y399743D03*
X323644Y399643D03*
X331090Y424304D03*
X331900Y419317D03*
X336740Y417069D03*
X328290Y424304D03*
X324940Y413899D03*
X334420Y428660D03*
X326190Y448621D03*
X329120Y449203D03*
X327780Y445819D03*
X331360Y447306D03*
X322986Y467109D03*
X330115Y490303D03*
X335162Y502791D03*
X326740Y495763D03*
X329672Y502057D03*
X326170Y518386D03*
X335860Y516486D03*
X336010Y531598D03*
X329348Y533403D03*
X324927Y546013D03*
X328592Y541146D03*
X328352Y545412D03*
X325588Y541447D03*
X332408Y544097D03*
X323088Y561503D03*
X323188Y564503D03*
X330388Y565803D03*
X332388Y567703D03*
X328088Y567503D03*
X323931Y589733D03*
X323346Y621930D03*
X329110Y623514D03*
X330440Y639504D03*
X328032Y642674D03*
X337070Y639759D03*
X326350Y638968D03*
X332710Y642694D03*
X328760Y657144D03*
X327540Y653432D03*
X335610Y658177D03*
X332747Y655636D03*
X332190Y659883D03*
X329912Y662383D03*
X335915Y675011D03*
X335390Y667895D03*
X326890Y676159D03*
X327257Y672408D03*
X333180Y665611D03*
X335130Y670744D03*
X334313Y663113D03*
X327500Y667244D03*
X324970Y665128D03*
X337030Y677894D03*
X337798Y686721D03*
X324120Y703114D03*
X336110Y693934D03*
X331520Y701642D03*
X332720Y698170D03*
X330410Y712895D03*
X325560Y713391D03*
X329590Y724283D03*
X334640Y725035D03*
X338270Y733387D03*
X338460Y724585D03*
X326280Y775980D03*
X337800Y774677D03*
X346600Y38561D03*
X346150Y36030D03*
X353060Y61504D03*
X349490Y57698D03*
X352578Y74292D03*
X339750Y73383D03*
X340543Y88647D03*
X345463Y90837D03*
X353713Y93057D03*
X344873Y94847D03*
X343070Y99372D03*
X340450Y101914D03*
X343743Y120967D03*
X351503Y130972D03*
Y127972D03*
X341693Y286010D03*
X340792Y307107D03*
X353903Y314077D03*
X353841Y306194D03*
X339370Y329176D03*
X341910Y325739D03*
X344720D03*
X339600Y332076D03*
X343880Y356989D03*
X349110Y375767D03*
X352420Y375672D03*
X346020Y374075D03*
X343430Y385937D03*
X343770Y382166D03*
X351650Y420270D03*
X346862Y424850D03*
X345270Y452745D03*
X346750Y466532D03*
X352890Y479656D03*
X348000Y479150D03*
X352260Y483029D03*
X338762Y479636D03*
X339506Y482841D03*
X348220Y486484D03*
X352160Y502138D03*
X351250Y499752D03*
X348870Y501571D03*
X343420Y497966D03*
X353400Y507260D03*
X353460Y504536D03*
X348190Y511550D03*
X353120Y510003D03*
X350690Y516376D03*
X340902Y503742D03*
X352940Y518025D03*
X341512Y512429D03*
X350902Y512520D03*
X346350Y517286D03*
X340182Y531787D03*
X351110Y531835D03*
X340330Y541931D03*
X341011Y537828D03*
X342190Y565848D03*
X351964Y599332D03*
X340340Y638054D03*
X340669Y644827D03*
X348480Y638558D03*
X345580Y638109D03*
X347670Y642285D03*
X351722Y659319D03*
X340630Y655093D03*
X351730Y649206D03*
X353902Y667128D03*
X351730Y663450D03*
X340530Y675658D03*
X351720Y670018D03*
X338970Y670776D03*
X340870Y665042D03*
X353260Y688757D03*
X351810Y706800D03*
X339750Y695271D03*
X339010Y700406D03*
X338926Y697752D03*
X352400Y722132D03*
X339300Y716800D03*
X342230Y720936D03*
X341190Y712379D03*
X352010Y713968D03*
X342230Y709384D03*
X345610Y733982D03*
X354060Y734790D03*
X350720Y745722D03*
X344710Y785782D03*
X350450Y784982D03*
X363025Y12926D03*
X366159Y21822D03*
X361930Y60031D03*
X367300Y60442D03*
X365670Y64458D03*
X362133Y90877D03*
X367776Y91746D03*
X358343Y90948D03*
X369670Y99845D03*
X361470Y101757D03*
X354943Y104191D03*
X354448Y108092D03*
X367350Y123927D03*
X365283Y128125D03*
X364220Y296795D03*
X365970Y299194D03*
X356835Y313894D03*
X369280Y300916D03*
X367220Y303202D03*
X369040Y316735D03*
X369934Y322946D03*
X365026Y332478D03*
X362540Y361443D03*
X354690Y377000D03*
X364645Y377065D03*
X364880Y384455D03*
X364580Y391273D03*
X366140Y407639D03*
X360350Y395873D03*
X355250Y420679D03*
X365850Y414874D03*
X368660Y449478D03*
X369500Y445873D03*
X354565Y451562D03*
X354750Y445325D03*
X369507Y464391D03*
X358182Y531231D03*
X357820Y534561D03*
X368825Y539776D03*
X369918Y592253D03*
X369848Y588903D03*
X360647Y602636D03*
X354973Y605588D03*
Y602588D03*
Y611588D03*
X361473Y620588D03*
X354973Y614588D03*
Y620588D03*
Y623588D03*
X361562Y645175D03*
X363530Y629727D03*
X365990Y645272D03*
X367870Y650239D03*
X364980Y655266D03*
X363340Y650512D03*
X361650Y658537D03*
X361580Y652755D03*
X368200Y672132D03*
X368100Y668133D03*
X361810Y675011D03*
X365620Y663069D03*
X361660Y671306D03*
X365380Y668972D03*
X365160Y672922D03*
X361760Y668716D03*
X367066Y681094D03*
X364320Y680434D03*
X367496Y690248D03*
X361510Y680886D03*
X362040Y684875D03*
X364649Y684022D03*
X364765Y687963D03*
X365090Y676923D03*
X367480Y705169D03*
X367614Y693053D03*
X361580Y703860D03*
X363590Y702324D03*
X364115Y692990D03*
X367520Y701710D03*
X367350Y713661D03*
X357830Y718682D03*
X354520Y728701D03*
X363460Y735388D03*
X364750Y727821D03*
X364090Y748565D03*
X354420Y749198D03*
X357610Y748302D03*
X366860Y739956D03*
X354870Y771388D03*
X360160Y775523D03*
X363300Y781303D03*
X367904Y778327D03*
X371180Y17789D03*
X370960Y20577D03*
X381907Y21507D03*
X383280Y59940D03*
X376006Y60991D03*
X383247Y64141D03*
X373560Y63973D03*
X372776Y91746D03*
X382087Y103647D03*
X380483Y99047D03*
X378733Y105987D03*
X384863Y95437D03*
X376100Y108780D03*
X376723Y94178D03*
X378183Y124904D03*
X374040Y304980D03*
X373640Y301078D03*
X370460Y305908D03*
X371090Y303487D03*
X384248Y319157D03*
X372080Y330574D03*
X379560Y374955D03*
X379720Y372257D03*
X378830Y386352D03*
X382620Y391882D03*
X379300Y380862D03*
X379286Y378015D03*
X379750Y383965D03*
X382190Y388077D03*
X376600Y408045D03*
X382680Y408202D03*
X371260Y412879D03*
X383750Y437058D03*
X372320Y439514D03*
X371950Y430527D03*
X378910Y430874D03*
X371080Y448276D03*
X372710Y445705D03*
X375190Y463996D03*
X381239Y467171D03*
X371080Y481589D03*
X374207Y479329D03*
X381760Y496004D03*
X374203Y491029D03*
X376540Y498385D03*
X383617Y517862D03*
X373538Y520213D03*
X376528Y520138D03*
X379733Y549392D03*
X370309Y550322D03*
X377150Y543151D03*
X376490Y540574D03*
X382596Y537379D03*
X382333Y540414D03*
X385410Y566122D03*
X373448Y589053D03*
X373518Y592403D03*
X383034Y640267D03*
X373218Y634217D03*
X382580Y637413D03*
X379093Y657739D03*
X376650Y654157D03*
X379492Y650239D03*
X376089Y646156D03*
X373680Y662417D03*
X376087Y670156D03*
X377211Y673197D03*
X379461Y675246D03*
X379462Y666156D03*
X379791Y679454D03*
X376946Y689985D03*
X377681Y694244D03*
X377679Y701168D03*
X377669Y706237D03*
X377100Y697218D03*
X371170Y711574D03*
X382960Y711431D03*
X372110Y720308D03*
X376190Y711259D03*
X375548Y731459D03*
X375834Y727459D03*
X377840Y724388D03*
X376770Y734898D03*
X373500Y748457D03*
X392600Y20548D03*
X389240D03*
X397655Y21336D03*
X392250Y59899D03*
X389690Y60665D03*
X401310Y61439D03*
X397790Y61360D03*
Y69610D03*
X390355Y75775D03*
X401220Y65155D03*
X392493Y92647D03*
X400163Y99177D03*
X391310Y99570D03*
X399613Y104657D03*
X391233Y96093D03*
X398088Y128455D03*
X393088D03*
X399598Y260251D03*
X398258Y252341D03*
X394378Y260501D03*
X399608Y275211D03*
X393458Y282931D03*
X392508Y275581D03*
X398038Y292571D03*
X399880Y319568D03*
X390080Y331575D03*
X389740Y404725D03*
X395740Y407528D03*
X393370Y411618D03*
X392076Y470970D03*
X387080Y486400D03*
X385940Y482478D03*
X388890Y480439D03*
X386410Y477576D03*
X389670Y477262D03*
X388982Y496939D03*
X395690Y512774D03*
X396350Y532016D03*
X396558Y522251D03*
X396470Y527847D03*
X396048Y540127D03*
X395922Y536127D03*
X396590Y549310D03*
X399590Y553502D03*
X390000Y567345D03*
X396520Y567444D03*
X393596Y567630D03*
X401091Y587054D03*
X398386Y587126D03*
X401422Y597270D03*
Y599770D03*
X398822Y600399D03*
X391447Y611973D03*
X394389Y604053D03*
X401353Y624007D03*
X399223Y644930D03*
X395701Y637430D03*
X399440Y637340D03*
X394380Y643389D03*
X396366Y653229D03*
X399363Y653588D03*
X389856Y645705D03*
X386173Y665065D03*
X391938Y672320D03*
X392097Y676231D03*
X399873Y666411D03*
X396550Y680266D03*
X399829Y690191D03*
X400968Y686699D03*
X400408Y681193D03*
X390660Y686923D03*
X391910Y696742D03*
X392080Y692796D03*
X391740Y705957D03*
X398620Y701411D03*
X390950Y701922D03*
X396150Y708926D03*
X400730Y721954D03*
X394840Y711437D03*
X404310Y65213D03*
X410713Y76187D03*
X404813Y93887D03*
X407303Y95117D03*
X408072Y109146D03*
X404738Y260421D03*
X402948Y253251D03*
X405970Y256489D03*
X401618Y267351D03*
X403148Y270191D03*
X405248Y272731D03*
X403628Y292201D03*
X408790Y317049D03*
X411240Y316482D03*
X414870Y455166D03*
Y450976D03*
X406352Y471405D03*
X410607Y485620D03*
X413607D03*
X409985Y508431D03*
X413138Y504813D03*
X413222Y508054D03*
X411439Y516956D03*
X407865Y516627D03*
X405348Y506316D03*
X402458Y505903D03*
X401556Y508937D03*
X409251Y521763D03*
X412088Y521721D03*
X407776Y527426D03*
X405954Y532502D03*
X404336Y545280D03*
X408486Y537333D03*
X416515Y547602D03*
X404578Y551838D03*
X408736Y551529D03*
X413342Y556219D03*
X406884Y594176D03*
X406881Y591322D03*
X412783Y605500D03*
X416454Y621319D03*
X413105Y613739D03*
X403904Y618333D03*
X410085Y618329D03*
X409520Y637387D03*
X414760Y636225D03*
X403970Y642364D03*
X406100Y631851D03*
X413535Y646804D03*
X411982Y660285D03*
X413718Y655267D03*
X410918Y649363D03*
X413966Y675624D03*
X415218Y664203D03*
X411675Y672654D03*
X411065Y667516D03*
X414183Y686151D03*
X411862Y688027D03*
X413643Y680004D03*
X412250Y683196D03*
X411149Y678387D03*
X412878Y693183D03*
X414550Y707464D03*
X414318Y700979D03*
X414810Y696968D03*
X402540Y710649D03*
X412080Y719034D03*
X414080Y721334D03*
X415730Y710897D03*
X406720Y723395D03*
X409010Y726147D03*
X415780Y747078D03*
X421893Y123537D03*
X421640Y228403D03*
Y223403D03*
X428405Y245194D03*
X424961Y241203D03*
X418905Y245694D03*
X426992Y250016D03*
X422528Y253531D03*
X426335Y267062D03*
X418575Y263691D03*
X420858Y261331D03*
X427817Y258829D03*
X421728Y279141D03*
X428748Y275222D03*
X418588Y286681D03*
X421128Y292601D03*
X423178Y284601D03*
X427909Y286759D03*
X427468Y292287D03*
X421710Y424527D03*
X430340Y416573D03*
X432450Y418766D03*
X422120Y418288D03*
X432960Y414886D03*
X422080Y414644D03*
Y410454D03*
X421770Y433187D03*
X422860Y441790D03*
X422760Y445581D03*
X425870Y449509D03*
X422460Y449467D03*
X429670Y449552D03*
X419420Y453168D03*
X428747Y463314D03*
X419420Y457358D03*
X428747Y468770D03*
X431280Y514223D03*
X431356Y516836D03*
X422050Y517028D03*
X425999Y516211D03*
X424873Y513921D03*
X426068Y546048D03*
X417979Y545352D03*
X428039Y548119D03*
X421461Y547703D03*
X420883Y556729D03*
X428039Y556539D03*
X423861Y556535D03*
X431145Y556608D03*
X424904Y586283D03*
X429340Y596874D03*
X425151Y608429D03*
X431520Y607039D03*
X420245Y636004D03*
X417422Y637592D03*
X432180Y647458D03*
X425334Y656419D03*
X422007Y652732D03*
X423623Y645396D03*
X422026Y656883D03*
X429820Y656709D03*
X421080Y665945D03*
X422222Y675226D03*
X426100Y667884D03*
X427900Y679709D03*
X430861Y679156D03*
X422981Y690351D03*
X430862Y691156D03*
X430813Y687156D03*
X427210Y691934D03*
X423055Y696713D03*
X430618Y699156D03*
X430667Y703156D03*
X430731Y707156D03*
X430813Y695156D03*
X427230Y707377D03*
X426391Y701173D03*
X423242Y707949D03*
X425590Y695895D03*
X421350Y694003D03*
X430738Y711156D03*
X427130Y717871D03*
X421730Y717398D03*
X429240Y721014D03*
X424410Y718429D03*
X417330Y717420D03*
X431440Y723955D03*
X420290Y733741D03*
X423900Y736055D03*
X424200Y733399D03*
X426440Y724240D03*
X421690Y779548D03*
X417880Y786361D03*
X428250Y772054D03*
X426900Y779752D03*
X442380Y75513D03*
X439670Y70044D03*
X446920Y78358D03*
X447715Y97926D03*
X446522Y146932D03*
X444550Y184057D03*
X442520Y223623D03*
X441580Y250730D03*
X443212Y240957D03*
X441498Y266731D03*
X441792Y259473D03*
X445540Y288853D03*
X445890Y283317D03*
X438340Y403375D03*
X439150Y400930D03*
X443240Y401984D03*
X446830Y400551D03*
X445900Y403460D03*
X436370Y410543D03*
X444020Y410374D03*
X439830D03*
X446660Y413325D03*
X446950Y417162D03*
X440900Y446260D03*
X436710D03*
X444850Y446337D03*
X438390Y456129D03*
X438520Y452324D03*
X433720Y449467D03*
X444920Y485259D03*
X447770Y485290D03*
X437716Y476295D03*
X445366Y490657D03*
X445199Y494590D03*
X439749Y506523D03*
X439762Y515540D03*
Y523757D03*
X447781Y523888D03*
X434605Y521488D03*
X442763Y549595D03*
X445838Y538085D03*
X435998Y539726D03*
X434203Y542897D03*
X438722Y538842D03*
X441063Y540563D03*
X448329Y534995D03*
X441326Y556050D03*
X437832Y556374D03*
X434187Y556444D03*
X442240Y553337D03*
X441230Y587341D03*
X447830Y588739D03*
X446378Y582681D03*
X435319Y600123D03*
X440040Y608537D03*
X437120Y612933D03*
X448460Y625960D03*
X445604Y629045D03*
X437100Y643793D03*
X446500Y645075D03*
X443850Y634754D03*
X439250Y630973D03*
X434681Y642639D03*
X435420Y647117D03*
X437509Y648996D03*
X435972Y655595D03*
X444700Y651900D03*
X445270Y660832D03*
X447210Y665143D03*
X436000Y675706D03*
X435539Y671628D03*
X436445Y667628D03*
X447161Y673564D03*
X444458Y669350D03*
X440688Y684438D03*
Y689438D03*
X440690Y702386D03*
X440688Y694438D03*
X442650Y719485D03*
X446260Y722014D03*
X444530Y723917D03*
X440660Y712065D03*
X439200Y722093D03*
X442120Y724781D03*
X447680Y733564D03*
X444370Y770152D03*
X434540Y778500D03*
X441006Y785297D03*
X458120Y44721D03*
X464170Y56436D03*
X458598Y77967D03*
X461516Y78275D03*
X461594Y99342D03*
X449538Y105144D03*
X453168D03*
X453940Y98586D03*
X460412Y105704D03*
X457912D03*
X462912D03*
X461880Y150596D03*
X454763Y183503D03*
X453340Y185670D03*
X457482Y183523D03*
X462790Y183489D03*
X459000Y200500D03*
X450650Y203785D03*
X453620Y245162D03*
X459990Y245930D03*
X456800Y259233D03*
X459108Y253181D03*
X449860Y267121D03*
X456530Y256034D03*
X449860Y272121D03*
X452900Y281647D03*
X453810Y289325D03*
X451790Y300129D03*
X448970Y403846D03*
X451950Y402434D03*
X463540Y495717D03*
X457537Y495546D03*
X454770Y495587D03*
X450813Y492993D03*
X463565Y515723D03*
X452895Y510061D03*
X449402Y515514D03*
X451504Y529734D03*
X450540Y521331D03*
X463991Y531504D03*
X451325Y525981D03*
X456722Y529536D03*
X454022Y541052D03*
X463031Y543563D03*
X453917Y550069D03*
X450367Y540720D03*
X453700Y545047D03*
X453854Y555069D03*
X455890Y592792D03*
X450778Y583106D03*
X462270Y612911D03*
X459690Y626423D03*
X464050Y633877D03*
X458903Y644884D03*
X461997Y654507D03*
X463178Y647483D03*
X460587Y669424D03*
X457138Y663251D03*
X463020Y661023D03*
X464330Y663251D03*
X458820Y674137D03*
X459950Y722720D03*
X453960Y723142D03*
X449060Y721761D03*
X457060Y722427D03*
X460822Y712620D03*
X451820Y712210D03*
X454070Y714226D03*
X455410Y734113D03*
X450410Y733682D03*
X451320Y725044D03*
X461565Y785806D03*
X463750Y780452D03*
X454120Y785923D03*
X475310Y59746D03*
X475030Y63879D03*
X479450Y63721D03*
X471500Y138000D03*
X473200Y140300D03*
X468400Y135800D03*
X470324Y133424D03*
X474813Y162220D03*
X467473Y159766D03*
X473951Y157235D03*
X473950Y172124D03*
X475760Y168747D03*
X472670Y166398D03*
X473580Y177859D03*
X474630Y174843D03*
X480220Y185766D03*
X475770Y186451D03*
X468452Y197934D03*
X471300Y201900D03*
X476400Y203100D03*
X478000Y212500D03*
X466200Y207300D03*
X471795Y267941D03*
X464810Y311253D03*
X470090Y332824D03*
X475190Y339013D03*
X465913Y402659D03*
X465883Y399834D03*
X480118Y479107D03*
Y474107D03*
X466307Y495676D03*
X467677Y510055D03*
X467496Y513179D03*
X466587Y515764D03*
X467586Y506807D03*
X471804Y561085D03*
Y556085D03*
X471190Y593964D03*
X468740Y585897D03*
X469890Y596580D03*
X473294Y613207D03*
X476320Y629280D03*
X465580Y641417D03*
X469229Y638135D03*
X475820Y635422D03*
X474946Y659376D03*
X468810Y652180D03*
X479512Y649436D03*
X468540Y655799D03*
X466980Y667059D03*
X469977Y676496D03*
X468260Y664366D03*
X469467Y679915D03*
X479409Y682305D03*
X479354Y677054D03*
X477710Y722299D03*
X466620Y714137D03*
X473940Y714184D03*
X470550Y724034D03*
X473560Y724951D03*
X465850Y733428D03*
X476980Y736594D03*
X476160Y734205D03*
X471780Y786300D03*
X486810Y60785D03*
X483240Y60546D03*
X487030Y68075D03*
X488438Y109623D03*
X492955Y99440D03*
X494355Y108674D03*
X491875Y125222D03*
X487140Y123397D03*
X484350Y112811D03*
X487020Y119754D03*
X494910Y133316D03*
X487857Y152147D03*
X488570Y147486D03*
X492424Y142234D03*
X494467Y148867D03*
X487740Y161235D03*
X488220Y157515D03*
X490130Y163086D03*
X493670Y171871D03*
X489040Y169483D03*
X482500Y184169D03*
X487080Y180918D03*
X482980Y181071D03*
X488850Y175419D03*
X494210Y175035D03*
X487839Y194142D03*
X487464Y198566D03*
X488017Y203716D03*
X486370Y189279D03*
X487168Y214568D03*
X491320Y231809D03*
X492700Y223800D03*
X484169Y272867D03*
X484780Y314090D03*
X494850Y315733D03*
X480830Y333921D03*
X486300Y422150D03*
X481300D03*
X495500Y447465D03*
X482880Y467935D03*
Y462935D03*
X492260Y482826D03*
X494980Y482979D03*
X490334Y497342D03*
X485510Y536673D03*
X483209Y545250D03*
Y550250D03*
X490661Y547148D03*
X489962Y540849D03*
X483838Y566194D03*
Y556148D03*
Y561148D03*
Y571194D03*
X485738Y587125D03*
X490738D03*
X481340Y593296D03*
X494238Y600441D03*
X490600Y608136D03*
X489800Y600200D03*
X487832Y624429D03*
X490040Y622140D03*
X491380Y639279D03*
X495900Y641804D03*
X480310Y642224D03*
X492310Y650516D03*
X482180Y646278D03*
X481253Y654837D03*
X493020Y646701D03*
X484700Y660355D03*
X482398Y673087D03*
X482544Y668042D03*
X491044Y667604D03*
X491060Y671604D03*
X490120Y662703D03*
X492770Y665090D03*
X492294Y682347D03*
X483056Y679628D03*
X481227Y685366D03*
X491167Y687507D03*
X481227Y691366D03*
X494340Y691623D03*
X491067Y699656D03*
X491380Y694656D03*
X490900Y706145D03*
X481227Y696366D03*
X495560Y694781D03*
X488180Y719244D03*
X490890Y714898D03*
X488090Y710545D03*
X480620Y734244D03*
X480770Y778125D03*
X485870Y776087D03*
X491720Y776713D03*
X495110Y771733D03*
X502900Y57670D03*
X496955Y99958D03*
X508955Y99978D03*
X500955Y100139D03*
X504955Y99830D03*
X500310Y109211D03*
X497430Y124024D03*
X504750Y111749D03*
X509691Y112938D03*
X499456Y128666D03*
X509710Y127269D03*
X500215Y136449D03*
X502183Y156709D03*
X500963Y162261D03*
X496360Y167221D03*
X501040Y177297D03*
X498940Y179744D03*
X510000Y173500D03*
X502999Y180541D03*
X499154Y194198D03*
X509100Y191900D03*
X505580Y192555D03*
X499225Y205296D03*
X506234Y207368D03*
X504941Y227859D03*
X498867Y227773D03*
X499405Y242877D03*
X507000Y239000D03*
X504160Y255584D03*
X511070Y310719D03*
X509140Y338005D03*
X497111Y388567D03*
X502111D03*
X509486Y433829D03*
X497818Y440265D03*
X506456Y446928D03*
X502938Y463823D03*
X505843Y465018D03*
X498119Y470011D03*
X511230Y499059D03*
X506230D03*
X498920Y523803D03*
X503958Y529405D03*
X504613Y525200D03*
X501331Y528932D03*
X503338Y549825D03*
Y544825D03*
X500138Y563025D03*
Y558625D03*
X500338Y566425D03*
X500438Y574925D03*
X500419Y578644D03*
X500538Y572025D03*
X500338Y569425D03*
X500538Y588525D03*
X505738Y590525D03*
X500098Y608885D03*
X509238Y608515D03*
X508024Y613598D03*
X500538Y600925D03*
X504980Y616425D03*
X508400Y617803D03*
X502080Y622999D03*
X498350Y627580D03*
X505780Y642543D03*
X501120Y633249D03*
X510700Y634300D03*
X496690Y633589D03*
X501940Y644073D03*
X504836Y657097D03*
X503680Y659666D03*
X505690Y654419D03*
X508061Y645381D03*
X504295Y649612D03*
X498040Y675306D03*
X498870Y668324D03*
X504114Y670830D03*
X496453Y670876D03*
X501914Y675624D03*
X504241Y665809D03*
X497320Y665216D03*
X506376Y687436D03*
X506470Y683512D03*
X496577Y684553D03*
X505580Y679105D03*
X496277Y678185D03*
X501540Y681970D03*
X506409Y691373D03*
X500710Y706582D03*
X497350Y699767D03*
X506092Y697575D03*
X510608Y717448D03*
X499842Y710582D03*
X499452Y714582D03*
X498080Y733252D03*
X509855Y724107D03*
X500260Y729094D03*
X501604Y733003D03*
X501890Y746663D03*
X507935Y785704D03*
X511770Y779940D03*
X499270Y776431D03*
X504440Y772548D03*
X513120Y72069D03*
X512955Y100428D03*
X524955Y99359D03*
X516955Y100333D03*
X520955Y100444D03*
X512878Y108635D03*
X519625Y108543D03*
X526835Y108314D03*
X525570Y124623D03*
X516146Y113121D03*
X522111Y113310D03*
X518640Y125539D03*
X518725Y170525D03*
X512600Y178900D03*
X515600Y172800D03*
X521320Y178184D03*
X516100Y178100D03*
X526621Y177079D03*
X512200Y204200D03*
X526443Y194116D03*
X514500Y194300D03*
X525293Y191705D03*
X515231Y191334D03*
X520015Y194584D03*
X523593Y198171D03*
X512200Y196000D03*
X520068Y207142D03*
X516551Y214987D03*
X512160Y217073D03*
X526657Y207363D03*
X524405Y212531D03*
X514766Y208222D03*
X515675Y234555D03*
X524675Y234766D03*
X517189Y226229D03*
X517670Y247527D03*
X515675Y254098D03*
X525480Y268959D03*
X518590Y310129D03*
X526250Y310940D03*
X519650Y320384D03*
X522420Y315475D03*
X517260Y315978D03*
X523930Y321642D03*
X514400Y340829D03*
X520510Y337299D03*
X527438Y340353D03*
X526440Y422428D03*
X527300Y417368D03*
X517929Y439676D03*
X523667Y438452D03*
X522379Y431974D03*
X512867Y443679D03*
X516353Y443517D03*
X523838Y442723D03*
X525603Y480187D03*
X525638Y484023D03*
X519938Y493125D03*
X524938D03*
X514430Y511801D03*
X519430D03*
X518938Y540425D03*
X521938Y540325D03*
X516380Y540364D03*
X525338Y540125D03*
X516738Y562425D03*
X513738D03*
X515413Y590950D03*
X524638Y590225D03*
X520228Y590335D03*
X525570Y602466D03*
X514058Y605055D03*
X523800Y611145D03*
X520370Y625158D03*
X526300Y623621D03*
X518920Y615387D03*
X511910Y638722D03*
X514320Y641085D03*
X515438Y649996D03*
X525692Y654862D03*
X517328Y655529D03*
X521516Y650576D03*
X517806Y670102D03*
X517222Y673917D03*
X518800Y665776D03*
X526610Y672286D03*
X515541Y661845D03*
X526430Y664730D03*
X518382Y678247D03*
X515429Y692278D03*
X526600Y679117D03*
X517888Y687901D03*
X518947Y685122D03*
X527111Y686052D03*
X515429Y697278D03*
X512548Y722093D03*
X514620Y713193D03*
X517443Y717011D03*
X517775Y711203D03*
X522865Y711178D03*
X514498Y716473D03*
X516940Y735683D03*
X521800Y732667D03*
X514420Y733131D03*
X524576Y733227D03*
X512610Y747115D03*
X525110Y774395D03*
X519440Y772861D03*
X542180Y93534D03*
X539510Y108742D03*
X536955Y100257D03*
X532955Y108669D03*
X528955Y99781D03*
X532955Y100604D03*
X535960Y112850D03*
X527613Y113373D03*
X542700Y112881D03*
X538655Y151415D03*
X538294Y159415D03*
X529272Y178311D03*
X542002Y180100D03*
X539500Y196500D03*
X536232Y192086D03*
X529592Y192999D03*
X533474Y196500D03*
X541657Y207645D03*
X532320Y209470D03*
X538525Y213425D03*
X532500Y206500D03*
X534208Y227832D03*
X528105Y230594D03*
X536972Y242993D03*
X536476Y238993D03*
X535772Y250076D03*
X539267Y267102D03*
X532794Y282068D03*
X530119Y280101D03*
X528680Y317349D03*
X541380Y340358D03*
X543110Y333848D03*
X536180Y341432D03*
X536170Y336603D03*
X531795Y340409D03*
X531430Y337074D03*
X527603Y337208D03*
X540700Y418852D03*
X541650Y422280D03*
X536440Y421973D03*
X530940Y422207D03*
X529968Y440216D03*
X529028Y430469D03*
X535352Y440414D03*
X540141Y442994D03*
X534738Y445523D03*
X541838Y450723D03*
X538038Y488323D03*
X533038D03*
X543280Y491040D03*
X530438Y529525D03*
X541538Y529625D03*
X534401Y529562D03*
X528138Y539925D03*
X540701Y590162D03*
X527638Y590325D03*
X535776Y590487D03*
X530338Y590325D03*
X529408Y603485D03*
X540540Y601008D03*
X538828Y602945D03*
X542848Y602975D03*
X535048Y602885D03*
X541980Y620227D03*
X527828Y615387D03*
X532420Y615484D03*
X539471Y632476D03*
X530779Y637354D03*
X532479Y633588D03*
X541440Y647594D03*
X531970Y650491D03*
X542424Y654821D03*
X536557Y655498D03*
X539120Y670129D03*
X529525Y669349D03*
X529899Y661020D03*
X539734Y675020D03*
X539830Y667332D03*
X531599Y689838D03*
X533270Y679351D03*
X531597Y697509D03*
X535272Y711217D03*
X535062Y708679D03*
X530012Y708618D03*
X543193Y710787D03*
X539577Y721891D03*
X537503Y710088D03*
X528388Y722903D03*
X540062Y708779D03*
X532940Y734810D03*
X531029Y733142D03*
X539650Y780942D03*
X529300Y771341D03*
X533600Y778780D03*
X555938Y97292D03*
X551454Y97154D03*
X547480Y96632D03*
X557995Y110244D03*
X546306Y110193D03*
X550490Y112989D03*
X552173Y138528D03*
X550599Y132596D03*
X550550Y151682D03*
X558059Y154254D03*
X558348Y142511D03*
X551464Y143862D03*
X550604Y168072D03*
X550370Y157461D03*
X557668Y176534D03*
X555510Y173872D03*
X551395Y174172D03*
X555836Y179259D03*
X546000Y180000D03*
X544500Y197500D03*
X546000Y192000D03*
X549909Y207060D03*
X557909Y207537D03*
X555750Y212029D03*
X544500Y207000D03*
X545424Y226722D03*
X546690Y233066D03*
X544990Y231086D03*
X549488Y233003D03*
X549358Y230153D03*
X552120Y232388D03*
X552050Y229124D03*
X550040Y243929D03*
X545703Y245725D03*
X545981Y236287D03*
X550090Y247079D03*
X545116Y266847D03*
X547929Y258102D03*
X557207Y274828D03*
X551341Y274262D03*
X545223Y276895D03*
X557207Y280328D03*
X555072Y289563D03*
X557222Y285109D03*
X553690Y340829D03*
X547340Y339103D03*
X552090Y388953D03*
X548470Y378127D03*
X549760Y407251D03*
X553230D03*
X553750Y410420D03*
X544500Y422583D03*
X557017Y438968D03*
X549574Y432582D03*
X555140Y445940D03*
X546384Y445107D03*
X547488Y452373D03*
X554550Y469674D03*
X545513Y469740D03*
X543338Y459323D03*
X547638Y462356D03*
X546038Y457523D03*
X546250Y490302D03*
X544370Y510267D03*
Y515267D03*
X554860Y531701D03*
X549920Y527242D03*
X551161Y547148D03*
X545138Y539725D03*
X551538Y540325D03*
X551338Y544225D03*
Y551100D03*
X551438Y563825D03*
X551238Y571725D03*
X547000Y590163D03*
X551238Y584025D03*
X543850Y590313D03*
X550149Y604639D03*
X543400Y625963D03*
X552350Y614028D03*
X558281Y637840D03*
X551030Y637200D03*
X543400Y635615D03*
X549314Y647594D03*
X551230Y652844D03*
X555356Y665156D03*
Y669156D03*
X555308Y673156D03*
X551283Y670800D03*
X555357Y689156D03*
X555284Y685156D03*
X555235Y681156D03*
X555308Y677156D03*
X551283Y699243D03*
X555150Y697156D03*
X555271Y693156D03*
X547542Y711523D03*
X544934Y720820D03*
X550535Y721903D03*
X555551Y722342D03*
X557488Y713709D03*
X553725Y717251D03*
X550004Y709559D03*
X555062Y708679D03*
X545062D03*
X553193Y724847D03*
X546566Y724119D03*
X544082Y724460D03*
X549049Y724412D03*
X557426Y724436D03*
X557978Y734053D03*
X545300Y783152D03*
X550940Y771858D03*
X554870Y779438D03*
X566090Y109136D03*
X560938Y97195D03*
X569559Y103123D03*
X565938Y96820D03*
X563230Y150222D03*
X564076Y145372D03*
X563410Y165289D03*
X563274Y162169D03*
X562195Y159015D03*
X563129Y178369D03*
X559646Y174476D03*
X569682Y195199D03*
X572782D03*
X569874Y231795D03*
X572690Y226569D03*
X572020Y222393D03*
X567980Y222353D03*
X568410Y226647D03*
X561258Y230153D03*
X566248Y230283D03*
X563506Y232027D03*
X564274Y279395D03*
X566774Y275195D03*
X566876Y289890D03*
X561525Y298192D03*
X560865Y285434D03*
X565953Y301635D03*
X565310Y412700D03*
X565977Y456156D03*
X566059Y460956D03*
X572440Y464323D03*
Y469323D03*
X562340Y484252D03*
X573840Y512108D03*
X564370Y504117D03*
Y509117D03*
X567493Y532225D03*
X562308Y536895D03*
X566298Y548465D03*
X563188Y541925D03*
X566338Y554235D03*
X561174Y564471D03*
X565858Y576195D03*
X561198Y581793D03*
X566378Y567725D03*
X561608Y571775D03*
X565398Y584765D03*
X568163Y595115D03*
X561568Y589355D03*
X574071Y606204D03*
X568930Y607754D03*
X566053Y627509D03*
X571650Y625998D03*
X574730Y625521D03*
X565647Y637705D03*
X565556Y632431D03*
X571790Y646799D03*
X559440Y650767D03*
X566950Y659439D03*
X563850Y659575D03*
X563840Y653515D03*
X565168Y664614D03*
Y674614D03*
Y669614D03*
X563586Y682137D03*
X563577Y692284D03*
X563441Y676872D03*
X565168Y679614D03*
X563393Y686908D03*
X565168Y689614D03*
Y694614D03*
Y699614D03*
X560544Y718091D03*
X569604Y721248D03*
X574190Y717805D03*
X564319Y721587D03*
X562540Y713454D03*
X560062Y708679D03*
X570614Y713237D03*
X565062Y708679D03*
X571232Y732545D03*
X566798Y734023D03*
X569680Y771106D03*
X560150Y781347D03*
X562700Y772391D03*
X572720Y777184D03*
X588943Y98963D03*
X589308Y103990D03*
X580501Y138336D03*
X583829Y132232D03*
X583547Y128232D03*
X587968Y138765D03*
X581565Y154969D03*
X583970Y144589D03*
X580180Y148894D03*
X579540Y143304D03*
X579897Y161355D03*
X582792Y167632D03*
X581915Y179955D03*
X585580Y210516D03*
X583707Y220762D03*
X587707Y220728D03*
X579707Y229395D03*
X585579Y230095D03*
X576105Y231626D03*
X581474Y274795D03*
X575880Y293016D03*
X575908Y295606D03*
X588607Y305034D03*
X576650Y311446D03*
X581650D03*
X585984Y323246D03*
X579788Y354743D03*
X589070Y423525D03*
X578830Y448192D03*
X588153Y459599D03*
X578840Y512108D03*
X583890Y537093D03*
X576208Y542405D03*
X575838Y548935D03*
X588540Y557418D03*
X584413Y563198D03*
X583538Y552225D03*
X575038Y554725D03*
X575138Y559825D03*
X577778Y556355D03*
X578110Y582149D03*
X582023Y571242D03*
X578399Y585696D03*
X588780Y611056D03*
X586810Y603344D03*
X577000Y620029D03*
X585500Y620926D03*
X588780Y616056D03*
X588950Y650070D03*
X583930Y652439D03*
X579020Y658250D03*
X577217Y652002D03*
X576987Y660180D03*
X580740Y653286D03*
X580637Y663629D03*
X576846Y675985D03*
X579076Y669603D03*
X576520Y667750D03*
X589050Y680160D03*
X579980Y683140D03*
X576644Y679562D03*
X578030Y690236D03*
X577010Y682718D03*
X576519Y687665D03*
X589500Y690546D03*
X579151Y707857D03*
X588151D03*
X584101Y707893D03*
X576442Y705492D03*
X585400Y697289D03*
X584312Y710716D03*
X579220Y720776D03*
X585693Y722428D03*
X583440Y724927D03*
X577570Y734118D03*
X580510Y724421D03*
X587170Y773768D03*
X579240Y775147D03*
X603158Y91535D03*
X601374Y94048D03*
X604543Y94886D03*
X598123Y102023D03*
X595318Y98854D03*
X593850Y103755D03*
X592392Y100623D03*
X595345Y120216D03*
X605070Y123991D03*
X600118Y112568D03*
X592938Y117657D03*
X595438Y138130D03*
X592938Y140689D03*
Y133232D03*
X594938Y127893D03*
X593537Y161023D03*
X592917Y171906D03*
X593277Y179955D03*
X591707Y221095D03*
Y230162D03*
X595374Y236795D03*
X592858Y247079D03*
X593459Y240780D03*
X594067Y265168D03*
X594174Y256695D03*
X593874Y262395D03*
X590874Y275195D03*
X594374Y271395D03*
X596574Y276393D03*
X593607Y305034D03*
X590984Y323246D03*
X598551Y329541D03*
X601450Y326509D03*
X604338Y338285D03*
X600770Y358702D03*
X597440Y391690D03*
X594860Y395088D03*
X600680Y412780D03*
X590720Y456076D03*
X591100Y450128D03*
X605800Y463167D03*
X603819Y485332D03*
X598670Y508170D03*
X603010Y527908D03*
X596560Y536108D03*
X606300Y551844D03*
X604820Y555040D03*
X604437Y557956D03*
X596050Y557563D03*
X592437Y566543D03*
X601043Y567781D03*
X605396Y590552D03*
X605286Y584152D03*
X605290Y594166D03*
X596401Y589852D03*
X593867Y595695D03*
X602314Y607641D03*
Y602641D03*
X593867Y600695D03*
X605010Y641435D03*
X600980Y641533D03*
X591279Y656223D03*
X596998Y658008D03*
X591840Y659568D03*
X596470Y655231D03*
X602332Y671156D03*
X600736Y668425D03*
X593142Y663828D03*
X600719Y675156D03*
X597300Y663128D03*
X600690Y691896D03*
X600727Y681876D03*
X602020Y679156D03*
X600727Y686876D03*
X604220Y703774D03*
X600650Y707835D03*
X592960Y703291D03*
X601856Y711479D03*
X606146Y713145D03*
X601813Y715579D03*
X598880Y719232D03*
X595950Y708997D03*
X594170Y719290D03*
X603938Y753623D03*
X606270Y774615D03*
X597530Y780191D03*
X592480Y771514D03*
X610543Y107678D03*
X617925Y114064D03*
X613432Y153528D03*
X610415Y237441D03*
X617778Y238873D03*
X612974Y269095D03*
X609150Y328514D03*
X616490Y327534D03*
X607671Y344818D03*
X619190Y336986D03*
X608306Y359971D03*
X611848Y359784D03*
X607855Y352341D03*
X618581Y354818D03*
X617592Y362539D03*
X620238Y364369D03*
X609078Y388557D03*
X619014Y408353D03*
X609078Y393557D03*
X612641Y397478D03*
Y402478D03*
X611050Y423087D03*
X621399Y420400D03*
X611130Y417928D03*
X616258Y422211D03*
X610580Y448662D03*
X609370Y452974D03*
X610010Y456581D03*
X617980Y460408D03*
X613470Y537495D03*
X616320Y537066D03*
X610070Y557588D03*
X621937Y558276D03*
X621840Y555040D03*
X609060Y552101D03*
X610821Y566494D03*
X621937Y567143D03*
X609026Y579132D03*
X617270Y580443D03*
X611520Y596594D03*
X612270Y586543D03*
X612493Y607666D03*
X611254Y617943D03*
X612370Y614143D03*
X615690Y625536D03*
X616730Y633290D03*
X608310Y641603D03*
X611572Y629894D03*
X620510Y639427D03*
X616471Y636215D03*
X613796Y648705D03*
X612950Y656140D03*
X607620Y647169D03*
X615700Y657757D03*
X613200Y661577D03*
X620160Y670594D03*
X615940Y666862D03*
X610693Y679333D03*
X610570Y691156D03*
X610550Y686640D03*
X610810Y683933D03*
X612670Y681438D03*
X612811Y688422D03*
X608975Y708094D03*
X612914Y707630D03*
X610540Y697964D03*
X618020Y700000D03*
X610570Y695156D03*
X607380Y699671D03*
X617930Y703520D03*
X620480Y693827D03*
X609070Y721917D03*
X616070Y720838D03*
X613730Y717663D03*
X620670Y722216D03*
X620830Y717516D03*
X609840Y713617D03*
X619080Y772610D03*
X619030Y778682D03*
X612260Y783106D03*
X609347Y778624D03*
X626380Y85117D03*
X624020Y83243D03*
X623750Y87130D03*
X626380Y88518D03*
X623725Y90422D03*
X626180Y91919D03*
X623820Y93654D03*
X626320Y96084D03*
X623610Y97125D03*
X626180Y99276D03*
X628838Y120216D03*
X628738Y133012D03*
X624800Y184953D03*
Y179953D03*
X634962Y200121D03*
Y195121D03*
X622470Y261628D03*
X635000Y265400D03*
X634212Y281670D03*
X624383Y292591D03*
X631672Y301066D03*
X632376Y305257D03*
X631702Y307880D03*
X632122Y312898D03*
X633773Y310439D03*
X635652Y313118D03*
X636962Y310928D03*
X623820Y321062D03*
X633470Y326710D03*
X628140Y317610D03*
X631860Y321455D03*
X627000Y327926D03*
X622890Y325227D03*
X633652Y315198D03*
X628141Y344818D03*
X630190Y336986D03*
X625190D03*
X624889Y357778D03*
X637738Y392034D03*
X636990Y386464D03*
X627022Y383713D03*
X634511Y389156D03*
X637614Y397259D03*
X630691Y405007D03*
X636938Y402885D03*
X630691Y410007D03*
X636586Y410910D03*
X633455Y427209D03*
X634578Y424964D03*
X635840Y449890D03*
X626250Y450248D03*
X631280Y446007D03*
X635120Y456136D03*
X630570Y451450D03*
X622100Y465822D03*
X625900Y461769D03*
X628250Y471142D03*
X632680Y466669D03*
X636010Y469995D03*
X630420Y491511D03*
X636170Y493028D03*
X622600Y488753D03*
X632157Y511230D03*
X625130Y534199D03*
X634530Y521565D03*
X622798Y546764D03*
X636890Y571351D03*
X624870Y573143D03*
X627084Y578257D03*
X634921Y580163D03*
X627047Y581066D03*
X623940Y628720D03*
X636890Y627095D03*
X629781Y628559D03*
X627986Y625895D03*
X630984Y624829D03*
X622510Y635544D03*
X634137Y631342D03*
X627146Y638932D03*
X623290Y641222D03*
X634137Y639352D03*
X630137Y639312D03*
X631930Y655254D03*
X633970Y723033D03*
X622290Y708516D03*
X628160Y722343D03*
X631690Y733744D03*
X635460Y735130D03*
X636170Y729335D03*
X630040Y745114D03*
X632300Y749755D03*
X636910Y745815D03*
X624010Y746351D03*
X629912Y769200D03*
X625010Y778281D03*
X636390Y775395D03*
X632030Y779137D03*
X632000Y775400D03*
X643957Y53688D03*
X639957Y53849D03*
X639200Y170100D03*
X639350Y250123D03*
X642932Y284768D03*
X640112Y285042D03*
X649995Y296433D03*
X652362Y306598D03*
X640647Y339854D03*
X648450Y338711D03*
X648838Y349785D03*
X642863Y358010D03*
X639838Y349818D03*
X646171Y364676D03*
X648425Y373474D03*
X652139Y377125D03*
X641236Y381616D03*
X645236Y377858D03*
X648493Y417221D03*
X648208Y427819D03*
X643208D03*
X653070Y427500D03*
X650822Y425295D03*
X641690Y443656D03*
X647280Y446851D03*
X653360Y446280D03*
X651080Y455238D03*
X652110Y465238D03*
X651840Y460012D03*
X648920Y457851D03*
X646600Y463571D03*
X648956Y469323D03*
X650521Y482930D03*
X647921Y475778D03*
X651395Y487265D03*
X650790Y497730D03*
X650150Y494337D03*
X638350Y507893D03*
X641842Y516730D03*
X646460Y512967D03*
X652690Y531693D03*
X640470Y523266D03*
X645040Y524444D03*
X645150Y535704D03*
X639673Y576888D03*
X651437Y578943D03*
X646732Y580781D03*
X641870Y580743D03*
X646870Y569443D03*
Y576243D03*
X644636Y627257D03*
X642795Y624818D03*
X648701Y624774D03*
X646940Y643448D03*
X641263Y631393D03*
X649173Y629876D03*
X646737Y639413D03*
X642737D03*
X647870Y649784D03*
X646580Y654775D03*
X651226Y666288D03*
X639940Y687841D03*
X640330Y684439D03*
X642999Y685781D03*
X644950Y719110D03*
X638890Y734879D03*
X652660Y749000D03*
X639920Y753526D03*
X646680Y755009D03*
X646500Y746300D03*
X650400Y770522D03*
X638470Y762212D03*
X649640Y757527D03*
X646370Y759252D03*
X647410Y767053D03*
X651690Y778099D03*
X640010Y778215D03*
X652212Y786700D03*
X655947Y53677D03*
X659947Y53722D03*
X655642Y144915D03*
Y149915D03*
X655695Y159567D03*
Y164567D03*
X655030Y228744D03*
Y223744D03*
X657838Y243407D03*
Y238407D03*
X656270Y299379D03*
X654962Y307698D03*
X654060Y302459D03*
X659350Y298810D03*
X655122Y315070D03*
X656730Y338633D03*
X659543Y377086D03*
X662390Y377039D03*
X653938Y364885D03*
X668925Y364887D03*
X663632Y366698D03*
X669215Y377488D03*
X658295Y417662D03*
X653649Y417582D03*
X668779Y417135D03*
X663674Y417999D03*
X655812Y424106D03*
X663339Y425601D03*
X658339D03*
X664450Y435739D03*
X658680Y446610D03*
X660458Y470932D03*
X659828Y465162D03*
X667774Y477992D03*
X661158Y486152D03*
X667070Y483608D03*
X662780Y477039D03*
X660518Y492862D03*
X662630Y500823D03*
X654240Y511568D03*
X653800Y505331D03*
X659933Y513927D03*
X664024Y513414D03*
X668573Y514155D03*
X668823Y532470D03*
X668627Y527718D03*
X667050Y535324D03*
X655445Y591918D03*
X658980Y610043D03*
X655978Y609635D03*
X656070Y612743D03*
X655688Y601761D03*
X663560Y625019D03*
X659600Y623785D03*
X655873Y615540D03*
X654221Y631425D03*
X657550Y655072D03*
X659978Y666274D03*
X665050Y680648D03*
X657340Y690286D03*
X655610Y706309D03*
X656505Y701191D03*
X657320Y723584D03*
X654050Y718086D03*
X656650Y713057D03*
X659200Y721454D03*
X659300Y734119D03*
X654000Y736400D03*
X655574Y728674D03*
X657570Y730414D03*
X658860Y727383D03*
X656000Y732400D03*
X657500Y761500D03*
X664460Y785890D03*
X657010Y786039D03*
X675927Y53779D03*
X669987Y53672D03*
X676590Y188198D03*
X680100Y188182D03*
X680220Y200725D03*
X678650Y203480D03*
X681770Y203514D03*
X682140Y191214D03*
Y194615D03*
X680310Y217357D03*
X678750Y214908D03*
X681870Y214942D03*
X679590Y352829D03*
X679430Y350013D03*
X677083Y375124D03*
X677946Y387211D03*
X678986Y392661D03*
X679138Y397985D03*
X680017Y403143D03*
X678838Y407785D03*
X673368Y416621D03*
X671056Y426300D03*
X672660Y441007D03*
X673740Y449887D03*
X682764Y444832D03*
X677070Y444820D03*
X672190Y457216D03*
X683112Y479786D03*
X679299Y491473D03*
X684876Y497385D03*
X674156Y503662D03*
X678450Y508438D03*
X680790Y504521D03*
X677160Y529422D03*
X675044Y524581D03*
X684620Y535923D03*
X678217Y536752D03*
X678360Y557426D03*
X673950Y557314D03*
X677850Y562515D03*
X673700D03*
X677730Y567706D03*
X673590Y567696D03*
X670940Y612070D03*
X683720Y631732D03*
X678386Y668420D03*
X673386D03*
X675100Y749300D03*
X672710Y746235D03*
X672500Y749179D03*
X684500Y786665D03*
X676390Y778439D03*
X677490Y782114D03*
X673290Y782855D03*
X677227Y786454D03*
X669320Y783845D03*
X681480Y777388D03*
X681164Y783461D03*
X669810Y786721D03*
X672500Y779579D03*
X683520Y789080D03*
Y792080D03*
X698150Y136791D03*
X687546Y154228D03*
X699990Y149631D03*
X700060Y144981D03*
X693520Y186376D03*
X697850Y186441D03*
X689820Y200159D03*
Y203491D03*
X689480Y191144D03*
Y194615D03*
X691970Y216820D03*
X691690Y212100D03*
X693540Y205721D03*
X697800Y205879D03*
X692010Y221158D03*
X687584Y233034D03*
X686686Y392522D03*
X687869Y386780D03*
X688118Y381043D03*
X686686Y397522D03*
X689527Y407843D03*
X685859Y403970D03*
X691037Y401739D03*
X689527Y412843D03*
X687130Y464132D03*
X691070Y464058D03*
X689017Y497282D03*
X694823Y498932D03*
X692520Y506898D03*
X696494Y513677D03*
X689729Y509580D03*
X696891Y507279D03*
X700719Y516954D03*
X686661Y519199D03*
X698438Y524890D03*
X686770Y543325D03*
X694150Y536155D03*
X690040Y535797D03*
X687183Y539585D03*
X687660Y631799D03*
X685640Y634154D03*
X698386Y667241D03*
X693386D03*
X699600Y776000D03*
X689700Y774500D03*
X711676Y51019D03*
X701770Y331938D03*
X702730Y455483D03*
X704550Y444407D03*
X715528Y459332D03*
X710768Y475972D03*
X715328Y481122D03*
X704766Y498880D03*
X713978Y498075D03*
X716021Y516945D03*
X700829Y504041D03*
X707736Y510140D03*
X707920Y505575D03*
X706361Y532632D03*
X716260Y525295D03*
X712820Y519647D03*
X701170Y538508D03*
X708258Y549815D03*
X713300Y578995D03*
X713190Y583032D03*
X712740Y593101D03*
X712732Y631749D03*
X716064D03*
X713742Y634373D03*
X708386Y669774D03*
X703386D03*
X713445Y677641D03*
X709500Y736800D03*
X704000Y770800D03*
X716245Y765576D03*
X719800Y24920D03*
X726500Y123466D03*
X726400Y130303D03*
X726470Y126659D03*
X726580Y455637D03*
X731570Y464043D03*
X726430Y465371D03*
X726830Y460815D03*
X727940Y469943D03*
X731340Y476723D03*
X720140Y478333D03*
X718431Y483368D03*
X721290Y484381D03*
X719370Y472436D03*
X725730Y486788D03*
X729640Y486848D03*
X727602Y500100D03*
X720150Y491632D03*
X719332Y515757D03*
X719761Y532432D03*
X728661Y558934D03*
X731251Y558975D03*
X726154Y559002D03*
X720445Y558990D03*
X723370Y558906D03*
X719092Y631682D03*
X717372Y634474D03*
X727830Y641829D03*
X728690Y649829D03*
X721100Y689400D03*
X718445Y677641D03*
X731200Y716200D03*
X730800Y728400D03*
X729500Y746300D03*
X721245Y765576D03*
X726925Y778490D03*
X731925D03*
X744760Y103711D03*
X744790Y106938D03*
X747710Y100293D03*
X738370Y123395D03*
X745070Y110183D03*
X738270Y130232D03*
X738340Y126588D03*
X747080Y129815D03*
X747600Y323527D03*
X745220Y327250D03*
X736310Y450774D03*
X737350Y464330D03*
Y459823D03*
X743364Y478975D03*
X743150Y483502D03*
X738130Y502748D03*
X732817Y489435D03*
X734575Y492575D03*
X745500Y492500D03*
X744020Y566143D03*
X744090Y575066D03*
X743951Y578833D03*
X744050Y571834D03*
X747470Y585542D03*
X747460Y582318D03*
X744000Y647919D03*
X733210Y645829D03*
X732540Y653829D03*
X751080Y100293D03*
X754580Y124020D03*
X748070Y110209D03*
X751180D03*
X754610Y127247D03*
X750930Y129815D03*
X750430Y314330D03*
X750350Y311343D03*
X750700Y323771D03*
X753230Y328262D03*
X759400Y334839D03*
X754850Y335055D03*
X755500Y337791D03*
X758494Y455532D03*
X748723Y455332D03*
X758500Y469500D03*
X751730Y583047D03*
X765250Y357789D03*
X765610Y361194D03*
G54D17*
X20859Y109561D03*
X78740Y30708D03*
X73740Y20708D03*
X713661D03*
X708661Y30708D03*
X703661Y20708D03*
X712975Y155655D03*
Y165455D03*
Y173455D03*
Y234461D03*
Y244261D03*
Y252261D03*
X723275Y155655D03*
Y165455D03*
Y173455D03*
Y234461D03*
Y244261D03*
Y252261D03*
G54D46*
X556181Y81889D03*
G54D11*
X-44872Y125213D03*
Y141213D03*
Y232533D03*
D03*
Y248533D03*
D03*
Y738493D03*
Y754493D03*
X-26872Y125213D03*
Y141213D03*
Y232533D03*
D03*
Y248533D03*
D03*
Y738493D03*
Y754493D03*
G54D21*
X36024Y181225D03*
Y205257D03*
Y199249D03*
Y193241D03*
Y217272D03*
Y211264D03*
X41930Y184229D03*
Y202253D03*
Y190237D03*
Y208260D03*
G54D34*
X154038Y511386D03*
X153967Y517186D03*
X162335Y521906D03*
X155400Y533436D03*
X154246Y527468D03*
X162335Y528206D03*
X159186Y534504D03*
X154945Y539233D03*
X159185Y547103D03*
X154900Y548682D03*
X159186Y553402D03*
X157611Y557468D03*
X154410Y557990D03*
X178818Y274540D03*
X178085Y518755D03*
X168617Y525756D03*
X172371Y519783D03*
X174720Y531356D03*
X178117Y528187D03*
X178099Y550267D03*
X174105Y542290D03*
X167027Y539526D03*
Y536376D03*
X173217Y536556D03*
X181818Y274540D03*
X181232Y515607D03*
X187417Y508756D03*
X189007Y514846D03*
X187875Y534128D03*
X181232Y537654D03*
X184384Y543955D03*
X188927Y537836D03*
X190434Y546870D03*
X207309Y539953D03*
X216184Y268587D03*
X223709Y505353D03*
X214118Y528583D03*
X218751Y543835D03*
X233626Y502591D03*
X230476D03*
X243075D03*
X236776Y518339D03*
X233626Y508891D03*
Y515190D03*
X230476D03*
X233626Y518339D03*
X236776Y512040D03*
X243075Y508891D03*
X230476D03*
X236776Y515190D03*
X230476Y518339D03*
Y512040D03*
X239925Y518339D03*
X233626Y521489D03*
Y527788D03*
X230476Y534087D03*
X236776Y521489D03*
Y527788D03*
Y524639D03*
X230476D03*
X233626Y534087D03*
X239925Y527788D03*
Y524639D03*
X230476Y527788D03*
Y521489D03*
X239925Y534087D03*
Y521489D03*
X233626Y543536D03*
X239925Y540386D03*
Y543536D03*
X236776Y537236D03*
X230476D03*
Y543536D03*
Y540386D03*
X233626D03*
X236776Y543536D03*
X233626Y537236D03*
X239925D03*
X243075Y559284D03*
Y552984D03*
X252524Y502591D03*
X255673D03*
X249374D03*
X246224D03*
X255673Y512040D03*
X252524D03*
X255673Y508891D03*
Y505741D03*
X249374D03*
Y508891D03*
X252524Y505741D03*
Y508891D03*
X249374Y512040D03*
X246224D03*
X252524Y549835D03*
X255673D03*
X249374D03*
X246224Y559284D03*
Y556134D03*
Y562434D03*
X252554Y559314D03*
X262904Y293850D03*
X268943Y291086D03*
X274582Y502591D03*
X271402Y499441D03*
X271429Y496295D03*
X261972Y502591D03*
X268272Y512040D03*
X271422D03*
X265121Y508891D03*
X261972D03*
Y505741D03*
X265122Y512040D03*
X261972D03*
X265122Y505741D03*
X268272Y549836D03*
X271421D03*
X265122D03*
X261972D03*
X271421Y552985D03*
X274572Y556142D03*
X287173Y499445D03*
X277712Y502595D03*
X277725Y534092D03*
Y527792D03*
Y521493D03*
Y540391D03*
Y543541D03*
Y537241D03*
X290322Y549841D03*
X280872D03*
X679175Y464038D03*
X674353Y463842D03*
X683112Y464038D03*
Y483723D03*
X683113Y471941D03*
X683112Y487660D03*
X690986Y467975D03*
X687049Y479786D03*
X690986Y483723D03*
X687049Y471912D03*
X698683Y487517D03*
X690986Y487660D03*
X687049D03*
X692955Y502112D03*
X702797Y464038D03*
Y467975D03*
X706734Y471913D03*
Y483723D03*
X710671Y479786D03*
X706734Y475850D03*
X710671Y471913D03*
X702585Y483749D03*
X702797Y471912D03*
Y479786D03*
X706734D03*
G54D37*
X399606Y377165D03*
X413386Y363385D03*
X403543Y367322D03*
Y387008D03*
X413386Y390945D03*
X427166Y377165D03*
X423229Y367322D03*
Y387008D03*
G54D36*
X354348Y38554D03*
X393718D03*
G54D41*
X507489Y281538D03*
G54D51*
X605796Y204845D03*
X611702Y185690D03*
Y178997D03*
Y200690D03*
Y193997D03*
G54D53*
X711575Y143555D03*
Y195355D03*
Y222361D03*
Y274161D03*
X733975Y143555D03*
Y195355D03*
Y222361D03*
Y274161D03*
G54D48*
X590999Y77041D03*
Y84915D03*
Y92789D03*
X615657Y77041D03*
Y84915D03*
Y92789D03*
G54D44*
X524780Y28803D03*
X514780Y38803D03*
X524780D03*
X534780Y28803D03*
X544780D03*
X534780Y38803D03*
X544780D03*
X554780D03*
X587371Y28803D03*
X577371Y38803D03*
X587371D03*
X597371Y28803D03*
X607371D03*
X597371Y38803D03*
X607371D03*
X617371D03*
X639963D03*
X649963Y28803D03*
Y38803D03*
X659963Y28803D03*
X669963D03*
X659963Y38803D03*
X669963D03*
X679963D03*
G54D26*
X65900Y566403D03*
X66181Y562149D03*
X63930Y560181D03*
X66262Y553344D03*
X65989Y578115D03*
X66036Y574901D03*
X63670Y576040D03*
X69766Y582525D03*
X81491Y533191D03*
X80318Y544311D03*
X81585Y536382D03*
X80318Y541026D03*
X112386Y71874D03*
X114072Y480964D03*
X110400Y502223D03*
X110436Y499681D03*
X110472Y496888D03*
X113337Y502080D03*
X113372Y496888D03*
X113301Y499574D03*
X112575Y532934D03*
X113912Y541144D03*
X114005Y544358D03*
X112627Y536697D03*
X130350Y130400D03*
Y134167D03*
X126072Y480864D03*
X122018Y516353D03*
X135640Y134167D03*
X135590Y130449D03*
X139365Y516636D03*
X139402Y513707D03*
X299629Y623877D03*
X318968Y536052D03*
X319135Y591407D03*
X336088Y454511D03*
X325040Y480129D03*
X355150Y486758D03*
X368787Y472998D03*
X374203Y482079D03*
X377284Y473374D03*
X399060Y454322D03*
X399050Y450968D03*
X398800Y462248D03*
Y458058D03*
X405878Y294071D03*
X403130Y418091D03*
X406200Y417755D03*
X405980Y414630D03*
X405930Y411386D03*
X406140Y424766D03*
X406150Y433203D03*
X406530Y440667D03*
X406000Y444755D03*
X402900Y444842D03*
X413733Y490781D03*
X410733D03*
X407733D03*
Y493781D03*
Y496781D03*
Y499781D03*
X410733Y493781D03*
X413733D03*
X410733Y496781D03*
X413733D03*
X410733Y499781D03*
X413733D03*
X402499Y554143D03*
X418597Y273538D03*
X418698Y279631D03*
X418998Y289871D03*
X418718Y301181D03*
X423278Y525160D03*
X428874Y525193D03*
X417520Y525128D03*
X428874Y530627D03*
X417520Y531177D03*
X428745Y536999D03*
X423332Y536763D03*
X417617Y536773D03*
X454263Y77675D03*
X450917Y97566D03*
X452669Y157140D03*
X539438Y250323D03*
X589036Y548825D03*
X596530Y574903D03*
X596495Y578903D03*
X596484Y582903D03*
X596209Y586903D03*
X590898Y597158D03*
X590842Y608112D03*
X591023Y600384D03*
X605362Y609413D03*
X590646Y618751D03*
X609168Y554851D03*
X607077Y566915D03*
X632362Y565543D03*
X636868Y593141D03*
X630768Y593241D03*
X624468D03*
Y612141D03*
X624368Y605941D03*
Y599741D03*
X629868Y612241D03*
X635968D03*
X643012Y565243D03*
X651437Y569676D03*
X643568Y593241D03*
Y612341D03*
Y606641D03*
Y599541D03*
X638470Y639290D03*
X650928D03*
X665170Y595943D03*
X661396Y588900D03*
X664603Y601976D03*
X654645Y627064D03*
X667610Y617197D03*
X655170Y639432D03*
X681310Y666671D03*
X671400Y666151D03*
X685410Y621250D03*
X688340Y621294D03*
X692720Y670540D03*
X698830Y670652D03*
X703570Y673036D03*
X707660Y673204D03*
X713910Y681330D03*
X718510Y681526D03*
X718150Y763015D03*
X721100Y762903D03*
X727570Y775278D03*
X730990Y775334D03*
G54D32*
X130794Y493910D03*
X133731D03*
X128240Y666583D03*
X120909Y674490D03*
X141682Y269829D03*
X150787Y9246D03*
X158181Y11978D03*
X163518Y243987D03*
X162317Y249877D03*
X161918Y254287D03*
X162484Y276599D03*
X161767Y287242D03*
X162181Y303075D03*
X161687Y310355D03*
X162063Y327940D03*
X159564Y328013D03*
X161513Y317143D03*
X159285Y336220D03*
X164418Y348187D03*
X171310Y12450D03*
X180510Y233307D03*
X174138Y243873D03*
X167467Y243242D03*
X171668Y256287D03*
X175118Y274287D03*
X170617Y267326D03*
X175318Y278687D03*
X170510Y275522D03*
X177470Y294933D03*
X180254Y295023D03*
X175162Y293934D03*
X175659Y286984D03*
X176037Y309845D03*
X180254Y310663D03*
X178812Y324259D03*
X180342Y316469D03*
X175330Y318552D03*
X177359Y332553D03*
X174876Y336549D03*
X168110Y350642D03*
X178232Y430642D03*
X178217Y435317D03*
X193677Y243855D03*
X184318Y247612D03*
X194056Y256697D03*
X193735Y265857D03*
X188442Y252643D03*
X184829Y259139D03*
X190918Y277687D03*
X185991Y279041D03*
X186118Y270787D03*
X183698Y285693D03*
X193557Y294428D03*
X187812Y286352D03*
X184812Y292979D03*
X186254Y295023D03*
X194771Y302176D03*
X193812Y308619D03*
X195254Y310663D03*
X184754Y302843D03*
X193313Y325492D03*
X186296Y326366D03*
X192293Y340792D03*
X185195Y332852D03*
X184367Y337792D03*
X192519Y352761D03*
X182877Y430662D03*
X182879Y435312D03*
X212020Y234359D03*
X211935Y244085D03*
X198685Y240785D03*
X211028Y255696D03*
X210333Y265197D03*
X208129Y257519D03*
X206144Y252477D03*
X208289Y263639D03*
X208226Y269697D03*
X201667Y274542D03*
X199509Y278094D03*
X206299Y312598D03*
X209300Y322800D03*
X207310Y330149D03*
X208485Y332356D03*
X200905Y333776D03*
X201489Y336207D03*
Y339107D03*
X198987Y353137D03*
X206657Y356116D03*
X217135Y244085D03*
X219772Y252659D03*
X215761Y252833D03*
X224794Y256754D03*
X218153Y260697D03*
Y263697D03*
X223929Y263639D03*
X225199Y281098D03*
X216109Y274139D03*
X212599Y281098D03*
Y290548D03*
X225199Y287398D03*
X212599Y293698D03*
X222049Y290548D03*
X225199Y309448D03*
Y299998D03*
Y303148D03*
X222049Y309448D03*
X212599Y299998D03*
Y303148D03*
X222049Y312598D03*
X218899Y309448D03*
X222049Y303148D03*
X215100Y322700D03*
X217129Y327207D03*
X215085Y325649D03*
X212600Y319100D03*
X217129Y324207D03*
Y336207D03*
X217067Y339542D03*
X217129Y333207D03*
X223010Y344242D03*
X228057Y352837D03*
X222777Y353066D03*
X214888Y352909D03*
X231749Y265139D03*
X239569Y257639D03*
X240910Y274742D03*
X233793Y269697D03*
X237799Y290548D03*
Y284248D03*
X231499Y287398D03*
X237800Y299998D03*
X231499Y309448D03*
X241258Y319123D03*
X240692Y344204D03*
X233055Y339936D03*
X230725Y331649D03*
X238084Y355992D03*
X259030Y123727D03*
X259443Y120773D03*
X255209Y260639D03*
X255359Y266557D03*
X257046Y279607D03*
X255205Y272755D03*
X244109Y277996D03*
X250399Y290548D03*
X244099Y284248D03*
X250399D03*
X244099Y293698D03*
X254334Y298728D03*
X247249Y303148D03*
X244118Y309387D03*
X247281Y315727D03*
X248509Y339207D03*
X247218Y333049D03*
X255009Y338318D03*
X259444Y354291D03*
X246265Y355855D03*
X249541Y587156D03*
Y583156D03*
X246639Y608378D03*
Y605778D03*
X249640Y602519D03*
X246639Y624378D03*
Y621778D03*
Y616378D03*
Y613778D03*
X273660Y23037D03*
X273645Y27712D03*
X269620Y243240D03*
X263029Y259139D03*
X265073Y266697D03*
X263029Y265139D03*
X271811Y256687D03*
X271898Y263173D03*
X271944Y278363D03*
X264386Y280407D03*
X265944Y278363D03*
X274886Y272587D03*
X273386Y280407D03*
X270444Y270543D03*
X271886Y272587D03*
X268886D03*
X268944Y278363D03*
X262886Y288227D03*
X264386Y296047D03*
X271811Y303313D03*
X271944Y309643D03*
X262944D03*
X261386Y311687D03*
X262035Y322679D03*
X267883Y325837D03*
X268502Y344181D03*
X263576Y340898D03*
X274701Y333804D03*
X270326Y335795D03*
X269117Y352876D03*
X278305Y23057D03*
X278307Y27707D03*
X278354Y244281D03*
X290154Y244007D03*
X285934Y243931D03*
X282178Y244005D03*
X289254Y255688D03*
X286492Y258364D03*
X283660Y251542D03*
X281954Y255588D03*
X288954Y260788D03*
X276328Y264687D03*
X277886Y272587D03*
X280886D03*
X286010Y276042D03*
X282867Y281142D03*
X279386Y311687D03*
X285890Y311357D03*
X281461Y321744D03*
X280776Y326412D03*
X275660Y338857D03*
X281212Y338079D03*
X290190Y352480D03*
X278943Y346914D03*
X277718Y352687D03*
X282818D03*
X286711Y352668D03*
X283140Y346082D03*
X291066Y590488D03*
Y593088D03*
X300118Y250987D03*
X295910Y266706D03*
X295110Y262961D03*
X295307Y275439D03*
X294510Y280709D03*
X297782Y291966D03*
X295010Y286767D03*
X294888Y304456D03*
X294781Y309788D03*
X295200Y321473D03*
X294596Y328129D03*
X294218Y343587D03*
X294888Y335326D03*
X294618Y348287D03*
X293467Y352442D03*
X299121Y597542D03*
X311420Y250230D03*
X315410Y258656D03*
X313888Y566003D03*
X313141Y550821D03*
X313075Y553755D03*
X313108Y556556D03*
X313275Y559590D03*
X316788Y572903D03*
X316688Y569603D03*
X320367Y618071D03*
X314910Y627222D03*
X317722Y614646D03*
X329260Y603381D03*
X328930Y611691D03*
X383344Y590662D03*
Y593262D03*
X391630Y597900D03*
X410522Y593947D03*
X413022D03*
X412960Y618207D03*
X410315Y614782D03*
X624101Y296525D03*
X640448Y294422D03*
X643170Y294282D03*
X641227Y297070D03*
X644113Y297071D03*
X653352Y291388D03*
X640171Y311965D03*
X644105D03*
X651352Y323938D03*
X653162Y318398D03*
X650162D03*
X638166Y560972D03*
X638286Y557415D03*
X660899Y311515D03*
X654352Y323938D03*
X664870Y614543D03*
X656971Y660492D03*
X671129Y305579D03*
X671166Y302550D03*
X687049Y467975D03*
X698860D03*
Y471912D03*
X690986D03*
Y479786D03*
X687049Y483723D03*
X698860Y479786D03*
Y483723D03*
X752960Y653967D03*
X749520Y658372D03*
G54D38*
X414961Y98622D03*
G54D19*
X23628Y321764D03*
Y338300D03*
X434102Y232640D03*
Y311875D03*
X583913Y69167D03*
X608571D03*
G54D22*
X40749Y150808D03*
Y249194D03*
G54D28*
X76880Y143269D03*
X739968Y29361D03*
G54D33*
X151969Y98622D03*
G54D23*
X43898Y168544D03*
Y231457D03*
G54D40*
X481102Y34528D03*
G54D52*
X688977Y105315D03*
Y719488D03*
G54D30*
X98426Y105512D03*
Y719685D03*
G54D54*
X712975Y183255D03*
Y262061D03*
X723275Y183255D03*
Y262061D03*
G54D27*
X83740Y20708D03*
G54D47*
X590999Y69167D03*
X615657D03*
G54D20*
X36024Y187233D03*
X41930Y178221D03*
Y196245D03*
Y220276D03*
Y214268D03*
G54D29*
X86880Y143269D03*
X749968Y29361D03*
G54D18*
X25439Y303260D03*
Y356804D03*
G54D31*
X102362Y247244D03*
Y349606D03*
X354331Y247244D03*
Y349606D03*
G54D39*
X413386Y377165D03*
G54D25*
X66981Y59390D03*
X62981Y59440D03*
X57040Y73421D03*
X72890Y154349D03*
X81210Y261337D03*
X129860Y14571D03*
X131474Y43439D03*
X137500Y25494D03*
X147461Y38078D03*
X147497Y42983D03*
X145210Y60154D03*
X149157Y60010D03*
X141190Y597685D03*
X145880Y584125D03*
X144710Y598135D03*
X134450Y682978D03*
X134777Y738726D03*
Y734726D03*
X134720Y742382D03*
X153863Y15176D03*
X164139Y13027D03*
X154592Y21173D03*
X152412Y38112D03*
X152366Y42983D03*
X152789Y53124D03*
X161640Y403286D03*
X154307Y507507D03*
X154517Y513931D03*
X159185Y531356D03*
X153731Y520734D03*
X159185Y543953D03*
X155060Y545526D03*
X154945Y542383D03*
Y536083D03*
X162315Y553391D03*
X155109Y561153D03*
X154900Y551832D03*
X151900Y590454D03*
X157963Y643289D03*
X179235Y7369D03*
X171666Y7449D03*
X175280Y12401D03*
X174166Y7449D03*
X166639Y13027D03*
X169149Y50968D03*
X175290Y389582D03*
X174500Y383383D03*
X175993Y414924D03*
X178082Y537654D03*
X171053Y569411D03*
X179532Y600437D03*
X173432D03*
X165832Y600337D03*
Y606037D03*
Y613137D03*
X172532Y619537D03*
X178632Y619437D03*
X165832D03*
X177038Y647135D03*
X166388Y647435D03*
X189235Y7369D03*
X191735D03*
X181735D03*
X190700Y418325D03*
X186417Y518526D03*
X186467Y514036D03*
X184920Y508626D03*
X181232Y528205D03*
Y543953D03*
X184384Y537656D03*
X188383Y556895D03*
X184386Y553406D03*
X185032Y606737D03*
X184932Y600537D03*
X185032Y612937D03*
X184932Y619437D03*
X211760Y610915D03*
X207476Y608936D03*
X207010Y602472D03*
X211862Y617709D03*
X202450Y663633D03*
X216209Y488853D03*
X213209D03*
X224209Y494928D03*
X221591Y563371D03*
X223561Y561475D03*
X218859Y593093D03*
X219296Y604811D03*
X215699Y625977D03*
X215985Y633977D03*
X216107Y637977D03*
X215948Y629977D03*
X231209Y566282D03*
X245609Y517182D03*
X262798Y417886D03*
X267741Y491608D03*
X262009Y556153D03*
X284024Y499445D03*
X303722Y385367D03*
X301209Y488853D03*
X303709Y489353D03*
X307116Y385979D03*
X336057Y575657D03*
X369280Y415600D03*
X374560Y412421D03*
X401670Y93807D03*
X409060Y92095D03*
X468210Y401505D03*
X474130Y553659D03*
X474290Y563565D03*
X486640Y543687D03*
X486720Y563730D03*
X481380Y553210D03*
X481410Y573563D03*
X485890Y590563D03*
X489380Y590839D03*
X582920Y194220D03*
X588692Y192809D03*
X758223Y446532D03*
X757823Y451032D03*
G54D14*
X-35858Y731383D03*
X21881Y595792D03*
X17071Y658951D03*
X33841Y9183D03*
X28104Y30414D03*
X24411Y16186D03*
X34149Y44149D03*
X30282Y34564D03*
X28250Y438740D03*
X37990Y453022D03*
X28250Y472076D03*
X37990Y520218D03*
X38807Y543539D03*
X38349Y555730D03*
X34440Y597285D03*
X36930Y611082D03*
X35862Y617052D03*
X29964Y658951D03*
X45410Y21563D03*
X54860Y16952D03*
X43480Y34592D03*
X45578Y50478D03*
X54703Y122796D03*
X46811Y122928D03*
X54062Y257049D03*
X49244Y360352D03*
X49730Y412473D03*
X45530D03*
X52150Y414896D03*
X47900Y414660D03*
X44360Y414915D03*
X49640Y430237D03*
X45410Y430444D03*
X51350Y433695D03*
X47420Y433725D03*
X44360Y433729D03*
X49625Y478472D03*
Y480972D03*
X50330Y497940D03*
X53330D03*
X49645Y491804D03*
Y489304D03*
X47380Y494638D03*
X53622Y509276D03*
X53330Y506417D03*
Y503817D03*
X50330D03*
X46140Y541712D03*
X43850Y602797D03*
X50170Y636895D03*
X59524Y25922D03*
X68756Y167695D03*
X56190Y170026D03*
X59640Y161376D03*
X57257Y180712D03*
X55963Y199565D03*
X57749Y204326D03*
X56383Y218543D03*
X63720Y228683D03*
X56936Y223944D03*
X57624Y366105D03*
X66747Y466363D03*
X64050Y465689D03*
X61183Y465314D03*
X65438Y510666D03*
X61033Y510705D03*
X61003Y515110D03*
X65478D03*
X56148Y530809D03*
X67260Y546688D03*
X63300Y621755D03*
X63490Y630693D03*
X79360Y46044D03*
X82065Y73224D03*
X80845Y106859D03*
X81030Y172605D03*
X78850Y157866D03*
X82030Y191733D03*
X75236Y188946D03*
X75359Y201109D03*
X85876Y218939D03*
X78190Y214642D03*
X72150Y225148D03*
X78614Y229920D03*
X79217Y232861D03*
X79544Y267579D03*
X82368Y297135D03*
X72368Y287906D03*
X73917Y385722D03*
X74031Y393857D03*
X85951Y410263D03*
X83455Y489485D03*
Y491985D03*
X85955Y489485D03*
Y491985D03*
X83455Y494485D03*
X85955D03*
X81635Y517104D03*
Y513104D03*
X72216Y540493D03*
X73130Y601599D03*
X73180Y611184D03*
X80630Y689682D03*
X82847Y716068D03*
X82736Y791695D03*
Y788695D03*
X70925D03*
Y791695D03*
X97830Y66508D03*
X98531Y121340D03*
X90878Y177967D03*
X86560Y205852D03*
X96168Y231618D03*
X93200Y300734D03*
X99968Y367705D03*
X95968Y367814D03*
X98410Y421908D03*
X98470Y418834D03*
X101650Y428745D03*
Y425552D03*
Y433296D03*
Y436075D03*
X101590Y446203D03*
X101650Y443038D03*
X86726Y501997D03*
X88563Y491984D03*
Y489484D03*
Y494484D03*
X91458Y511853D03*
X98410Y680541D03*
X100223Y733207D03*
X94547Y788695D03*
Y791695D03*
X115628Y104405D03*
X106517Y210796D03*
X110490Y397362D03*
X116960Y394023D03*
X114207Y417910D03*
Y414910D03*
X105670Y411262D03*
X117980Y451981D03*
X118020Y455079D03*
X114372Y518898D03*
X109640Y611890D03*
X109410Y621425D03*
X109500Y616724D03*
X109260Y644687D03*
Y648989D03*
X117790Y667235D03*
X115748Y716275D03*
X114232Y791695D03*
Y788695D03*
X126460Y250160D03*
X126570Y256194D03*
X129660Y279890D03*
X130310Y269174D03*
X123160Y287060D03*
X129610Y287115D03*
X122729Y398001D03*
X127729D03*
X125229D03*
X128226Y413925D03*
X125726D03*
X123226D03*
X121080Y460060D03*
X124040Y459746D03*
X127060Y460040D03*
X121360Y472028D03*
X118720Y471989D03*
X132960Y550005D03*
X125340Y558090D03*
X129607Y686735D03*
X120357Y738889D03*
X120322Y742187D03*
X123518Y742030D03*
X146558Y74863D03*
X147570Y249033D03*
X147160Y242219D03*
X143150Y281123D03*
X137925Y290987D03*
X136130Y305640D03*
X137091Y301799D03*
X135730Y314543D03*
X134768Y319043D03*
X135224Y323543D03*
X136506Y332193D03*
X144058Y376025D03*
X135507Y421367D03*
X147820Y441929D03*
X145020Y576001D03*
X147753Y627557D03*
X145750Y630254D03*
X147750Y687539D03*
X143823Y682907D03*
X134753Y726161D03*
X137070Y728012D03*
X141791Y788695D03*
Y791695D03*
X161221Y89447D03*
X160040Y108844D03*
X162130Y129344D03*
X160449Y259605D03*
X158583Y285548D03*
X161918Y293869D03*
X162017Y324389D03*
X152058Y376016D03*
X160058Y375818D03*
X150524Y382808D03*
X161577Y436834D03*
X161563Y432521D03*
X158430Y568437D03*
X149860Y726626D03*
X177224Y49101D03*
X174724D03*
X177224Y51601D03*
X174724D03*
X172224Y49101D03*
Y54101D03*
X177224D03*
X174724D03*
X172224Y51601D03*
X177757Y88271D03*
X168308Y88412D03*
X180990Y108770D03*
X177210Y97657D03*
X165690Y98835D03*
X171950Y105105D03*
X167127Y120603D03*
X174213Y120569D03*
X171320Y243601D03*
X166189Y335285D03*
X167383Y341306D03*
X177604Y355155D03*
X177720Y352522D03*
X177029Y347811D03*
X177672Y358103D03*
X176058Y376568D03*
X168058Y376035D03*
X167951Y380551D03*
X170506Y424127D03*
X173151Y427552D03*
X172944Y448387D03*
X170444D03*
X179857Y477790D03*
X169293Y562358D03*
X171180Y652009D03*
X171270Y655650D03*
X179180Y675205D03*
X174761Y663816D03*
X178278Y705976D03*
Y701976D03*
Y697976D03*
Y709976D03*
X171689Y728920D03*
X173287Y791695D03*
Y788695D03*
X184843Y88467D03*
X191930Y88507D03*
X196000Y95568D03*
X195473Y108767D03*
X184170Y95213D03*
X186060Y100103D03*
X196010Y125188D03*
X186730Y121202D03*
X188821Y232784D03*
X189192Y243061D03*
X187404Y343998D03*
X186925Y355812D03*
X186908Y352760D03*
X184058Y376479D03*
X194231Y390267D03*
X194330Y396425D03*
X192676Y402961D03*
X182771Y424013D03*
X185271D03*
X182771Y421513D03*
X185271D03*
X192069Y444852D03*
X185747Y487664D03*
X188654Y573395D03*
X188200Y672526D03*
X196463Y685036D03*
X182163Y684555D03*
X194508Y704476D03*
X187798Y704513D03*
X185440Y712499D03*
X196144Y712602D03*
X187744Y708356D03*
X191930Y712624D03*
X194440Y735623D03*
X189940Y735681D03*
X185440D03*
X182674Y730521D03*
X199016Y88434D03*
X206103Y88207D03*
X202560Y107797D03*
X210203Y108457D03*
X206273Y98364D03*
X207070Y179744D03*
X207154Y175212D03*
X207041Y184502D03*
X207070Y188978D03*
X197243Y344518D03*
X206817Y358874D03*
X207274Y353124D03*
X202823Y376922D03*
X200439Y390168D03*
X203880Y385272D03*
X200488Y396425D03*
X200039Y448750D03*
Y451350D03*
X197809Y469953D03*
X200434Y478345D03*
X208710Y500856D03*
X211379Y501904D03*
X208050Y528883D03*
X209886Y539962D03*
X201509Y539853D03*
X199709Y551653D03*
X208109Y551053D03*
X209238Y674373D03*
X210023Y712842D03*
X201663Y712694D03*
X198940Y712499D03*
X212440Y735829D03*
X198940Y735681D03*
X207940D03*
X203440D03*
X200846Y788695D03*
Y791695D03*
X225990Y21219D03*
X221990D03*
X221600Y66317D03*
X225600D03*
X213190Y88414D03*
X220276Y88440D03*
X214573Y93771D03*
X219095Y108675D03*
X217040Y103121D03*
X226713Y122007D03*
X223561Y385108D03*
X214008Y385165D03*
X221438Y390655D03*
X226276Y460704D03*
X213994Y466054D03*
X214626Y516492D03*
X227329Y508894D03*
X216564Y528902D03*
X223453Y578087D03*
X216590Y570850D03*
X220428Y580271D03*
X221129Y642363D03*
X215768Y671993D03*
X224289Y680081D03*
X224360Y684366D03*
X213365Y692151D03*
X226610Y713482D03*
X216940Y736063D03*
X221440Y735934D03*
X225940Y724061D03*
X220532Y788695D03*
Y791695D03*
X212658D03*
Y788695D03*
X241990Y21219D03*
X229990D03*
X237600Y66317D03*
X241600D03*
X229600D03*
X233600D03*
X236360Y93931D03*
X236812Y88698D03*
X229725Y88719D03*
X243730Y103057D03*
X240355Y108757D03*
X239500Y100925D03*
X231910Y105731D03*
X235190Y96905D03*
X233268Y121742D03*
X233697Y353961D03*
X243940Y390885D03*
X236687Y385234D03*
X232172Y388814D03*
X240599Y440053D03*
X242915Y576539D03*
X239269Y597128D03*
X229809Y583627D03*
X229584Y652668D03*
X237451Y652761D03*
X243596Y671772D03*
X229895Y671672D03*
X240493Y692678D03*
X238348Y712469D03*
X243900Y724662D03*
X239440Y736140D03*
X230440Y736412D03*
X234940Y724325D03*
X240217Y788695D03*
Y791695D03*
X232343D03*
Y788695D03*
X249990Y21219D03*
X245990D03*
X257270Y29334D03*
X258300Y22289D03*
X253810Y63244D03*
X245600Y66317D03*
X249600D03*
X246073Y92197D03*
X256573Y94097D03*
X247870Y105821D03*
X250399Y296848D03*
X253611Y293765D03*
X254819Y332435D03*
X250466Y344381D03*
X245691Y341215D03*
X251334Y352857D03*
X250661Y384780D03*
X244196Y419610D03*
Y417010D03*
Y427610D03*
Y425010D03*
Y433010D03*
Y435610D03*
X253709Y586128D03*
X249462Y648383D03*
X257271Y671772D03*
X253398Y692357D03*
X254940Y712381D03*
X253340Y724726D03*
X248440Y736163D03*
X257440Y736041D03*
X252940Y736318D03*
X252028Y791695D03*
X271421Y7319D03*
X268579Y19365D03*
X265934Y16522D03*
X268372Y40782D03*
X265872D03*
X273873Y63167D03*
X269793D03*
X261750Y75886D03*
X267703Y89397D03*
X265830Y102566D03*
X264210Y96914D03*
X267020Y257079D03*
X265886Y271718D03*
X270430Y665576D03*
X269709Y672575D03*
X270140Y691038D03*
X265300Y702131D03*
X275440Y735626D03*
X261940Y735878D03*
X266440Y736030D03*
X270940Y735642D03*
X271713Y788695D03*
Y791695D03*
X259902D03*
X280699Y13908D03*
X278199D03*
X282180Y10253D03*
X285703Y9813D03*
X280699Y16408D03*
X278199D03*
X287476Y37125D03*
X290823Y63167D03*
X282023D03*
X277853D03*
X277000Y88323D03*
X286263Y88677D03*
X287595Y106109D03*
X279010Y104889D03*
X286710Y95717D03*
X276507Y295816D03*
X276687Y385100D03*
X283820Y396266D03*
X281142Y402379D03*
X276809Y471853D03*
X276347Y459741D03*
X284332Y472834D03*
X282298Y483803D03*
X289171Y661908D03*
X288880Y689467D03*
X278341Y717269D03*
X279940Y724126D03*
X289240Y724687D03*
X283990Y734977D03*
X279587Y791695D03*
X295307Y41260D03*
X295390Y44017D03*
X295610Y50299D03*
X295560Y52907D03*
X294903Y63167D03*
X306693D03*
X303053D03*
X298883D03*
X296093Y88477D03*
X302853Y89057D03*
X294800Y100593D03*
X295490Y97209D03*
X302370Y95215D03*
X293873Y130357D03*
X297668Y300709D03*
X298202Y374572D03*
X301240Y470885D03*
X291327Y466811D03*
X306220Y477125D03*
X296913Y514460D03*
X301457Y513837D03*
X291357Y586128D03*
X305602Y620685D03*
Y618185D03*
X299090Y634421D03*
X305200Y652883D03*
X301696Y701851D03*
Y699351D03*
X291790Y735976D03*
X306540Y724266D03*
X297940Y724377D03*
X302660Y736359D03*
X298160Y736489D03*
X291398Y792234D03*
X299272Y791695D03*
X314640Y63167D03*
X310483D03*
X318543D03*
X322713D03*
X314830Y92851D03*
X312183Y88837D03*
X321463Y88517D03*
X321643Y321928D03*
X309143D03*
X311643D03*
X314143D03*
X316643D03*
X319143D03*
X322765Y327721D03*
X322210Y336696D03*
X319323Y338320D03*
X309510Y344127D03*
X319666Y354376D03*
X309131Y374573D03*
X314860Y367656D03*
X315383Y387863D03*
X315533Y384749D03*
X316963Y467655D03*
X316956Y478833D03*
X313347Y570695D03*
X312641Y611556D03*
X307996Y611536D03*
X312656Y606881D03*
X307994Y606886D03*
X308102Y620685D03*
Y618185D03*
X307574Y633762D03*
X314790Y652049D03*
X317130Y653628D03*
X322440Y700130D03*
X320110Y703093D03*
X317580Y719996D03*
X307940Y736445D03*
X311440Y735831D03*
X315940Y735924D03*
X320440Y736031D03*
X311083Y791871D03*
X318957Y791695D03*
X336316Y31815D03*
X326353Y63167D03*
X336024Y88176D03*
X329643Y89887D03*
X336340Y99265D03*
X327950Y101057D03*
X323000Y94337D03*
X332453Y122297D03*
X331376Y299883D03*
X332700Y333089D03*
X334816Y367787D03*
X337316Y367758D03*
X337330Y372679D03*
X334816Y372609D03*
X325749Y418701D03*
X336218Y424850D03*
X325180Y432577D03*
X323154Y556367D03*
Y558867D03*
Y553867D03*
X337550Y558618D03*
Y556118D03*
Y553618D03*
X325841Y719731D03*
X336990Y735701D03*
X324940Y736067D03*
X329440Y735814D03*
X333940Y735895D03*
X339162Y9304D03*
Y11904D03*
X350411Y21277D03*
X339239Y24232D03*
X339471Y19373D03*
Y16773D03*
X339239Y26832D03*
X350198Y88277D03*
X343111Y88429D03*
X344770Y101718D03*
X351793Y105404D03*
X344073Y124397D03*
X351533Y124697D03*
X351373Y134367D03*
X345297Y284849D03*
X342955Y291523D03*
X354170Y308924D03*
X351500Y301795D03*
X342759Y599193D03*
X339616Y603438D03*
Y605938D03*
X339384Y611544D03*
X339600Y621293D03*
Y618693D03*
X339384Y614144D03*
X353298Y633903D03*
X351728Y653860D03*
X339930Y661219D03*
X340525Y686600D03*
X344780Y713349D03*
X343730Y724581D03*
X350180Y735880D03*
X350580Y724427D03*
X346516Y790294D03*
X358285Y21325D03*
X356550Y74767D03*
X366733Y88477D03*
X359646Y88174D03*
X360827Y108541D03*
X362300Y98674D03*
X367560Y120823D03*
X354580Y298101D03*
X357400Y307608D03*
X362660Y316986D03*
X357110Y329210D03*
X359410Y317080D03*
X359120Y331164D03*
X357040Y332970D03*
X360960Y389080D03*
X368943Y506356D03*
X366426Y527722D03*
Y530222D03*
Y532722D03*
X368238Y522673D03*
X365329Y546121D03*
X368694Y546159D03*
X367858Y657573D03*
X365070Y658065D03*
X362173Y665128D03*
X367399Y684652D03*
X367866Y677326D03*
X361646Y689228D03*
X364844Y698332D03*
X361786Y699128D03*
X361717Y695128D03*
X366510Y723622D03*
X361350Y720720D03*
X361490Y712505D03*
X363162Y739537D03*
X366430Y731459D03*
X357096Y732976D03*
X360246Y730819D03*
X363359Y743537D03*
X366201Y787976D03*
X354390Y790294D03*
X366201Y790976D03*
X379940Y17789D03*
X382990Y17519D03*
X380906Y88134D03*
X373820Y88400D03*
X384450Y108830D03*
X372620Y98355D03*
X384090Y98743D03*
X379160Y102923D03*
X374030Y95000D03*
X377363Y121108D03*
X376150Y430405D03*
X373850Y496585D03*
X379177Y509798D03*
X383924Y514797D03*
X385040Y521754D03*
X384588Y526069D03*
X382632Y530322D03*
Y527822D03*
Y532822D03*
X384485Y552365D03*
X382595Y554166D03*
X385573Y629998D03*
X371407Y641507D03*
X380101Y660239D03*
X375575Y739459D03*
X370430Y749138D03*
X376960Y788580D03*
Y791580D03*
X399002Y17519D03*
X393371Y72919D03*
X399804Y88778D03*
X397442Y90667D03*
X389400Y89232D03*
X399653Y108357D03*
X391536Y108990D03*
X398820Y95823D03*
X391190Y104173D03*
X388860Y98010D03*
X399150Y131773D03*
X391880Y131692D03*
X399858Y249711D03*
X399298Y257231D03*
X391998Y258251D03*
X392668Y272511D03*
X400928Y293151D03*
X396098Y283931D03*
X389107Y492097D03*
X400589Y611672D03*
X400587Y607022D03*
X398195Y620821D03*
X400695Y618321D03*
X398195D03*
X400695Y620821D03*
X392063Y624109D03*
X396940Y658078D03*
X396478Y661529D03*
X399911Y661325D03*
X400267Y684029D03*
X390000Y689724D03*
X389961Y682218D03*
X389350Y711288D03*
X414949Y75291D03*
X403739Y72783D03*
X404528Y88702D03*
X405688Y253581D03*
X405038Y267521D03*
X401728Y277251D03*
X409054Y483084D03*
X412260Y482881D03*
X405234Y611692D03*
X405249Y607017D03*
X405426Y626809D03*
X413930Y639810D03*
X410989Y652957D03*
X415834Y693272D03*
X409581Y711643D03*
X413940Y735665D03*
X421473Y160556D03*
Y157556D03*
X422698Y244301D03*
X422288Y250661D03*
X419038Y242611D03*
X427768Y253569D03*
X422178Y266891D03*
X428208Y262109D03*
X426948Y281051D03*
X422918Y289501D03*
X419071Y509283D03*
X422210Y605343D03*
X419221Y612253D03*
X422221Y619873D03*
X422470Y647852D03*
X425146Y672426D03*
X430140Y665660D03*
X417974Y663446D03*
X422510Y677836D03*
X430873Y684536D03*
X425173Y688588D03*
X423317Y705344D03*
X422940Y723802D03*
X420160Y724309D03*
X430940Y735895D03*
X426430Y735126D03*
X418440Y735930D03*
X421321Y791476D03*
X417384D03*
X446268Y69074D03*
X446088Y90159D03*
Y85159D03*
Y87659D03*
X434158Y122272D03*
X443448Y124552D03*
X441518Y122242D03*
X434158Y125092D03*
X444828Y122132D03*
X433253Y160737D03*
X433363Y157607D03*
X442580Y236459D03*
X447900Y265292D03*
X442148Y279361D03*
X442165Y271284D03*
X441076Y294906D03*
X441361Y300812D03*
X437887Y471073D03*
X437516Y587579D03*
X440135Y615808D03*
X433872Y645119D03*
X446980Y638774D03*
X446799Y657526D03*
X444403Y665963D03*
X446900Y714648D03*
X447240Y724780D03*
X439940Y735507D03*
X443940Y735681D03*
X435440Y735928D03*
X436440Y724710D03*
X441006Y791476D03*
X437069D03*
X450618Y69004D03*
X457583Y66384D03*
X462294Y87759D03*
Y85259D03*
Y90259D03*
X453298Y122254D03*
X450798D03*
X452158Y124582D03*
X458818Y122065D03*
Y125422D03*
X455292Y162797D03*
X455470Y166963D03*
X455913Y178698D03*
X452115Y195057D03*
X450576Y234431D03*
X454150Y249053D03*
X457165Y262368D03*
X449290Y276227D03*
X453780Y292411D03*
X461130Y408318D03*
X461080Y411451D03*
X463690Y451813D03*
X461590Y446700D03*
X461540Y449833D03*
X457702Y475480D03*
X460702D03*
X454702D03*
X463702D03*
X450899Y483452D03*
X460236Y581679D03*
X458600Y599200D03*
X453775Y600614D03*
X453935Y624739D03*
X456342Y649436D03*
X458650Y666543D03*
X463120Y681992D03*
X460530Y681874D03*
X459650Y685993D03*
X457730Y682010D03*
X456960Y685581D03*
X461960Y684394D03*
X453530Y736212D03*
X458050Y725053D03*
X462440Y735687D03*
X460691Y791476D03*
X456754D03*
X464767Y78145D03*
X466647Y91224D03*
X466682Y102410D03*
X474381Y125310D03*
X478088Y125219D03*
X474140Y408318D03*
X469590D03*
X465330D03*
X474080Y411451D03*
X469530D03*
X465270D03*
X480050Y419556D03*
X471540Y437214D03*
X473140Y439971D03*
X469500Y447730D03*
X467920Y451667D03*
X472210Y450267D03*
X465730Y449833D03*
X465790Y446700D03*
X479575Y467597D03*
X479754Y462988D03*
X466702Y475480D03*
X473153Y622451D03*
X478905Y659426D03*
X470190Y648693D03*
X479353Y668666D03*
X466049Y675327D03*
X471450Y736368D03*
X466440Y735987D03*
X471310Y733811D03*
X466440Y724465D03*
X474940Y747192D03*
X476439Y791476D03*
X488438Y100123D03*
X484068Y99980D03*
X490760Y154771D03*
X495300Y201600D03*
X491046Y207506D03*
X486738Y210434D03*
X488816Y242877D03*
X495140Y385762D03*
X486670Y426196D03*
X483685Y473522D03*
X483641Y479628D03*
X489938Y563425D03*
X490658Y579025D03*
X487398Y576665D03*
X490693Y570770D03*
X490538Y567825D03*
X485380Y596505D03*
X491100Y644351D03*
X491930Y654203D03*
X495622Y660178D03*
X491157Y675604D03*
X491189Y679656D03*
X494323Y687669D03*
X496000Y736152D03*
X483180Y736506D03*
X487940Y735681D03*
X491890Y735740D03*
X494850Y733252D03*
X480376Y791476D03*
X508904Y124063D03*
X502132Y146686D03*
X498875Y217172D03*
X499075Y235575D03*
X496123Y233500D03*
X504897Y390481D03*
X505819Y417473D03*
X510577Y417741D03*
X498238Y417825D03*
X502687Y417453D03*
X499551Y429636D03*
X502494Y436725D03*
X509464Y450265D03*
X505442Y458719D03*
X511070Y493380D03*
X511520Y496255D03*
X505740Y495880D03*
X511560Y513792D03*
X504613Y522050D03*
X500138Y543225D03*
X503448Y540235D03*
X505718Y542865D03*
X500038Y555925D03*
Y550725D03*
X510338Y571325D03*
X499868Y585725D03*
X505738Y600425D03*
X496140Y608883D03*
X504268Y608625D03*
X498666Y653012D03*
X502890Y736349D03*
X506105Y724132D03*
X500061Y791476D03*
X496124D03*
X518248Y137692D03*
X518477Y141401D03*
X527349Y152246D03*
X526875Y161838D03*
X511997Y207730D03*
X519183Y224173D03*
X519300Y220500D03*
X516625Y230075D03*
X517617Y422944D03*
X514820Y417617D03*
X526440Y432077D03*
X515780Y434039D03*
X513140Y452621D03*
X519440Y452321D03*
X526340D03*
X513140Y459721D03*
Y466021D03*
X525640Y473021D03*
X519640D03*
X513140D03*
X516353Y480708D03*
X519490Y496645D03*
X525698Y496724D03*
X522250Y513692D03*
X527138Y529525D03*
X523938Y528725D03*
X515110Y528785D03*
X519438Y543025D03*
X513480Y541499D03*
X513838Y556925D03*
X512354Y590825D03*
X519638Y600425D03*
X523538Y600325D03*
X527438D03*
X519830Y634663D03*
X515371Y658880D03*
X515425Y685783D03*
X518500Y723073D03*
X519440Y735681D03*
X512140Y736554D03*
X514901Y724120D03*
X523370Y724131D03*
X519746Y791476D03*
X515809D03*
X542248Y106333D03*
X527898Y147146D03*
X533483Y177449D03*
X533797Y180764D03*
X536676Y234993D03*
X536576Y246993D03*
X529527Y265584D03*
X529910Y419478D03*
X541440Y431787D03*
X536440Y431923D03*
X531440Y432178D03*
X542738Y455823D03*
X530038Y444323D03*
X533040Y453221D03*
X533740Y458021D03*
Y465021D03*
X542738Y463123D03*
X533740Y473021D03*
X540938Y473623D03*
X535729Y476632D03*
X539419Y491107D03*
X532934Y491384D03*
X530638Y539525D03*
X534638Y539825D03*
X541238Y539625D03*
X533038Y590325D03*
X536438Y600425D03*
X542438Y613723D03*
X538400Y613804D03*
X540048Y629641D03*
X535230Y648711D03*
X535485Y715182D03*
X537702Y735662D03*
X541940Y735681D03*
X528440D03*
X531845Y724095D03*
X539431Y791476D03*
X535494D03*
X547248Y106582D03*
X548367Y135415D03*
X548007Y139415D03*
X547543Y143415D03*
X558845Y158697D03*
X558768Y191223D03*
X553909Y207401D03*
X547927Y212190D03*
X558416Y210682D03*
X544700Y216100D03*
X547148Y220220D03*
X555707Y389146D03*
X543381Y448428D03*
X556771Y456156D03*
X556959Y443009D03*
X551140Y445789D03*
X556971Y460656D03*
X547340Y484025D03*
X548000Y509493D03*
X547880Y515743D03*
X544138Y530125D03*
X545413Y547950D03*
X551438Y561225D03*
X551538Y568525D03*
X550938Y587325D03*
X548138Y600425D03*
X544638Y600525D03*
X553619Y601204D03*
X546938Y613828D03*
X552849Y631652D03*
X545377Y647594D03*
X547346Y697581D03*
X544984Y699419D03*
X555148Y735583D03*
X550940Y735681D03*
X546440D03*
X555179Y791476D03*
X561909Y207393D03*
X571576Y246693D03*
X564676D03*
X571476Y260093D03*
X564676D03*
Y253693D03*
X567320Y415088D03*
X561610Y503885D03*
X560960Y510151D03*
X571830Y509411D03*
X567791Y528325D03*
X568068Y525306D03*
X561065Y543998D03*
X560838Y540325D03*
X574738Y579525D03*
X574537Y591325D03*
X574738Y587425D03*
X574645Y583525D03*
X565168Y684614D03*
X568215Y702343D03*
X568288Y715547D03*
X568908Y735883D03*
X573440Y735681D03*
X564438Y735853D03*
X560350Y735807D03*
X573440Y724053D03*
X568940Y724090D03*
X562395Y724557D03*
X559116Y791476D03*
X578938Y103123D03*
X583829Y117732D03*
X583661Y121836D03*
X584438Y160933D03*
X579707Y220662D03*
X578076Y246693D03*
Y253393D03*
Y260093D03*
X575874Y282395D03*
Y289895D03*
Y285995D03*
X583853Y313783D03*
X585584Y308881D03*
X579168Y313641D03*
X583737Y321204D03*
X575550Y463784D03*
X575650Y469996D03*
X579600Y508878D03*
X585013Y547959D03*
X575438Y545425D03*
X575238Y552025D03*
X575038Y567725D03*
X575538Y571725D03*
X574876Y575625D03*
X586369Y585801D03*
X579500Y625963D03*
X587440Y656958D03*
X576700Y655594D03*
X584903Y663828D03*
X586060Y682582D03*
X587040Y688218D03*
X586995Y694080D03*
X583440Y735856D03*
X587940Y735681D03*
X587963Y724108D03*
X577940Y724127D03*
X578802Y791476D03*
X574864D03*
X594920Y123370D03*
X592491Y175906D03*
X595707Y220995D03*
X597074Y239995D03*
X600874Y239795D03*
X604774Y249795D03*
X596774D03*
X600874D03*
X604674Y239995D03*
X592874Y250995D03*
X605674Y236295D03*
X596574Y268695D03*
X600674Y268795D03*
X604574D03*
X604926Y278476D03*
X604774Y271893D03*
X592201Y308988D03*
X591977Y319360D03*
X605746Y387837D03*
X605573Y393920D03*
X605798Y501238D03*
X596751Y532108D03*
X605521Y601097D03*
X594733Y653385D03*
X601588Y664798D03*
X592440Y723768D03*
X596860Y723422D03*
X601440Y735681D03*
X605938Y735665D03*
X596940Y735681D03*
X593004Y735662D03*
X598487Y791476D03*
X594550D03*
X618623Y108918D03*
X608274Y249795D03*
X608774Y239995D03*
X608274Y268795D03*
X613640Y336986D03*
X608869Y396959D03*
X608821Y403445D03*
X621760Y526967D03*
X609300Y531638D03*
X613541Y546764D03*
X614579Y645072D03*
X610651Y675156D03*
X614909Y671938D03*
X617235Y689036D03*
X621410Y696941D03*
X607020Y704644D03*
X611244Y709830D03*
X621254Y713788D03*
X617093Y709167D03*
X619590Y735383D03*
X614732Y735517D03*
X608791Y735775D03*
X618172Y791476D03*
X614235D03*
X610298D03*
X624358Y176090D03*
X632483Y192781D03*
X624950Y189801D03*
X632485Y202077D03*
X633633Y403717D03*
X633663Y411009D03*
X634945Y461888D03*
X635545Y465888D03*
X622199Y506535D03*
X634190Y538267D03*
X634251Y683493D03*
X623940Y723503D03*
X623960Y735141D03*
X628380Y735476D03*
X629983Y791476D03*
X633920D03*
X638970Y132241D03*
X646013Y358110D03*
X647440Y386383D03*
X647340Y393283D03*
X647440Y408383D03*
X647340Y400083D03*
X651138Y417385D03*
X641480Y430289D03*
X650079D03*
X646381Y478679D03*
X646105Y492010D03*
X646906Y505210D03*
X648077Y713569D03*
X653500Y732583D03*
X639928Y738905D03*
X658769Y143630D03*
X658767Y151013D03*
X658959Y165625D03*
X658972Y158337D03*
X667300Y188112D03*
X660700Y203282D03*
X669250Y203317D03*
X665320Y203247D03*
X664560Y195018D03*
Y191443D03*
X660770Y214951D03*
X665390Y214916D03*
X661160Y235485D03*
X658582Y222614D03*
X658601Y229770D03*
X661190Y246085D03*
X666270Y359134D03*
X660138Y365885D03*
X654340Y386283D03*
X661140D03*
X654840Y408483D03*
X661940Y408383D03*
X666312Y417742D03*
X656021Y427864D03*
X665766Y427868D03*
X664528Y463432D03*
X667428D03*
X666928Y468132D03*
X659740Y536019D03*
X668000Y676595D03*
X656254Y683277D03*
X663040Y688057D03*
X654514Y720674D03*
X656660Y736218D03*
X661479Y791476D03*
X665416D03*
X679927Y53881D03*
X670980Y77061D03*
X671810Y106472D03*
X670280Y188112D03*
X669320Y214986D03*
X672752Y366160D03*
X679552Y372873D03*
X669540Y386283D03*
X678099Y389915D03*
X674235Y379364D03*
X669440Y395183D03*
Y408483D03*
X669540Y402783D03*
X678338Y405185D03*
X683128Y451332D03*
X680228Y451432D03*
X670428Y463532D03*
X669728Y468032D03*
X672628D03*
X678315Y540752D03*
X669390Y695406D03*
X672630Y720752D03*
X688160Y64459D03*
X689500Y120441D03*
X691148Y140140D03*
X691280Y149571D03*
X691314Y145071D03*
X687571Y172292D03*
X687584Y251770D03*
X689864Y392130D03*
X687121Y407004D03*
X689864Y398141D03*
X686731Y413349D03*
X691161Y518684D03*
X691532Y559789D03*
Y563789D03*
Y567789D03*
Y571789D03*
Y575789D03*
Y579789D03*
Y583789D03*
Y587789D03*
X695600Y590788D03*
X689100Y680291D03*
X688510Y735294D03*
X707176Y50574D03*
X706380Y75482D03*
X708130Y106389D03*
X701687Y212132D03*
X700947Y216868D03*
X700994Y221368D03*
X707942Y448676D03*
X714639Y454872D03*
X712239Y452293D03*
X712281Y525785D03*
X710585Y539103D03*
X701023Y553658D03*
X710873Y563230D03*
X715282Y620282D03*
X711612Y620383D03*
X708450Y695489D03*
X705870Y721832D03*
X706575Y740425D03*
X704786Y791274D03*
X708723Y791092D03*
X709040Y787507D03*
X726160Y109316D03*
X726190Y105325D03*
X726160Y112508D03*
X731566Y442136D03*
X729942Y515757D03*
X720052Y620480D03*
X729500Y737400D03*
X721790Y791408D03*
X722590Y787885D03*
X738620Y109351D03*
X738650Y105360D03*
X738620Y112543D03*
X741401Y454832D03*
X742779Y487639D03*
X734460Y788654D03*
Y791654D03*
X762590Y106529D03*
X762630Y103302D03*
X757500Y474000D03*
X748300Y496800D03*
X766840Y561290D03*
X766920Y564080D03*
X766950Y558318D03*
X766820Y569897D03*
X766900Y567233D03*
Y572869D03*
X771110Y578643D03*
X770850Y575760D03*
X770710Y584054D03*
X770850Y587025D03*
G54D35*
X227326Y505741D03*
X230476D03*
X236776Y508891D03*
X252524Y527789D03*
Y524639D03*
X255673Y534088D03*
X252524D03*
X249374D03*
X255673Y524639D03*
Y527789D03*
X249374D03*
Y524639D03*
X255673Y537237D03*
X249374D03*
X252524D03*
X255673Y540387D03*
X249374D03*
X252524D03*
X255673Y565580D03*
Y552984D03*
Y556133D03*
Y559282D03*
Y562431D03*
X249344Y552984D03*
Y556134D03*
X265122Y502591D03*
X268272Y505741D03*
Y508891D03*
X261972Y521489D03*
X268272Y534088D03*
X265122D03*
X261972D03*
X268272Y524639D03*
Y527789D03*
X265122D03*
Y524639D03*
X261972D03*
Y527789D03*
X268272Y521489D03*
X265122D03*
X268272Y540387D03*
X265122D03*
X261972D03*
X265122Y537237D03*
X268272D03*
X261972D03*
X274571Y552985D03*
X265122D03*
X268272Y559291D03*
X271422Y562434D03*
X271421Y556135D03*
X271422Y559291D03*
X261973Y552985D03*
X261972Y562431D03*
X271422Y565583D03*
X290323Y534092D03*
X280874D03*
X287174D03*
X284024D03*
X280874Y537241D03*
Y543541D03*
X284024D03*
X287174Y540391D03*
Y543541D03*
X290323Y540391D03*
Y543541D03*
X287174Y559289D03*
X290323Y565589D03*
X284024Y565588D03*
X287174D03*
X290323Y559289D03*
Y562439D03*
Y556140D03*
X287174Y562438D03*
X280874D03*
X284024D03*
Y559289D03*
X277725Y552989D03*
X280874Y559289D03*
X277725Y556135D03*
Y559289D03*
X287174Y556139D03*
X280874Y552989D03*
X284024Y556139D03*
X287174Y552989D03*
X284024D03*
X293473Y534092D03*
Y540391D03*
Y565589D03*
Y562439D03*
Y559290D03*
G54D50*
X605796Y174845D03*
Y189845D03*
G54D16*
X10859Y109561D03*
G54D42*
X507489Y360278D03*
G54D45*
X546181Y81889D03*
G54D43*
X514780Y28803D03*
X554780D03*
X577371D03*
X617371D03*
X639963D03*
X679963D03*
G54D49*
X605796Y165160D03*
X609733Y215672D03*
G54D24*
X45282Y321764D03*
Y338300D03*
%LPC*%
G75*
G36*
G01X-36897Y131113D02*
G02X-34847I1025J-400D01*
G01X-33897D01*
G02Y130313I1025J-400D01*
G01X-34847D01*
G02X-36897I-1025J400D01*
G01X-37847D01*
G02Y131113I-1025J400D01*
G01X-36897D01*
G37*
G36*
G01Y238433D02*
G02X-34847I1025J-400D01*
G01X-33897D01*
G02Y237633I1025J-400D01*
G01X-34847D01*
G02X-36897I-1025J400D01*
G01X-37847D01*
G02Y238433I-1025J400D01*
G01X-36897D01*
G37*
G36*
G01X-34847D02*
G03X-36897I-1025J-400D01*
G01X-37847D01*
G03Y237633I-1025J-400D01*
G01X-36897D01*
G03X-34847I1025J400D01*
G01X-33897D01*
G03Y238433I1025J400D01*
G01X-34847D01*
G37*
G36*
G01Y748593D02*
G02X-36897I-1025J400D01*
G01X-37847D01*
G02Y749393I-1025J400D01*
G01X-36897D01*
G02X-34847I1025J-400D01*
G01X-33897D01*
G02Y748593I1025J-400D01*
G01X-34847D01*
G37*
G54D55*
G01X38493Y-241864D02*
Y-246864D01*
G01X37036Y-241864D02*
X39950D01*
G01X44860Y-246864D02*
X42326D01*
Y-241864D01*
X44860D01*
G01X43846Y-244281D02*
X42326D01*
G01X47426Y-241864D02*
Y-246864D01*
X49960D01*
G01X53793Y-247031D02*
X53666Y-246947D01*
Y-246781D01*
X53793Y-246697D01*
X53920Y-246781D01*
Y-246947D01*
X53793Y-247031D01*
G01Y-244781D02*
X53666Y-244697D01*
Y-244531D01*
X53793Y-244447D01*
X53920Y-244531D01*
Y-244697D01*
X53793Y-244781D01*
G01X58576Y-248531D02*
X57943Y-247697D01*
X57626Y-246864D01*
Y-243531D01*
X57943Y-242697D01*
X58576Y-241864D01*
G01X63993D02*
X63486Y-242031D01*
X63106Y-242447D01*
X62853Y-242947D01*
X62663Y-243614D01*
X62600Y-244364D01*
X62663Y-245114D01*
X62853Y-245781D01*
X63106Y-246281D01*
X63486Y-246697D01*
X63993Y-246864D01*
X64500Y-246697D01*
X64880Y-246281D01*
X65133Y-245781D01*
X65323Y-245114D01*
X65386Y-244364D01*
X65323Y-243614D01*
X65133Y-242947D01*
X64880Y-242447D01*
X64500Y-242031D01*
X63993Y-241864D01*
G01X67700Y-245864D02*
X68080Y-246447D01*
X68586Y-246781D01*
X69156Y-246864D01*
X69663Y-246781D01*
X70170Y-246364D01*
X70486Y-245864D01*
X70550Y-245364D01*
X70423Y-244781D01*
X69980Y-244364D01*
X69536Y-244197D01*
X68966D01*
G01X69536D02*
X69916Y-243947D01*
X70233Y-243531D01*
X70360Y-243031D01*
X70233Y-242531D01*
X69916Y-242114D01*
X69346Y-241864D01*
X68776Y-241947D01*
X68206Y-242281D01*
G01X74510Y-248531D02*
X75143Y-247697D01*
X75460Y-246864D01*
Y-243531D01*
X75143Y-242697D01*
X74510Y-241864D01*
G01X77900Y-245864D02*
X78280Y-246447D01*
X78786Y-246781D01*
X79356Y-246864D01*
X79863Y-246781D01*
X80370Y-246364D01*
X80686Y-245864D01*
X80750Y-245364D01*
X80623Y-244781D01*
X80180Y-244364D01*
X79736Y-244197D01*
X79166D01*
G01X79736D02*
X80116Y-243947D01*
X80433Y-243531D01*
X80560Y-243031D01*
X80433Y-242531D01*
X80116Y-242114D01*
X79546Y-241864D01*
X78976Y-241947D01*
X78406Y-242281D01*
G01X83190Y-242697D02*
X83570Y-242197D01*
X84013Y-241947D01*
X84520Y-241864D01*
X85153Y-242031D01*
X85596Y-242447D01*
X85723Y-242947D01*
X85660Y-243447D01*
X85406Y-243864D01*
X84140Y-244697D01*
X83570Y-245281D01*
X83190Y-246114D01*
X83063Y-246864D01*
X85723D01*
G01X89366D02*
X89493Y-245781D01*
X89683Y-244864D01*
X89936Y-244031D01*
X90253Y-243114D01*
X90760Y-241864D01*
X88226D01*
G01X93770Y-245197D02*
X95416D01*
G01X98490Y-242697D02*
X98870Y-242197D01*
X99313Y-241947D01*
X99820Y-241864D01*
X100453Y-242031D01*
X100896Y-242447D01*
X101023Y-242947D01*
X100960Y-243447D01*
X100706Y-243864D01*
X99440Y-244697D01*
X98870Y-245281D01*
X98490Y-246114D01*
X98363Y-246864D01*
X101023D01*
G01X103400Y-245864D02*
X103780Y-246447D01*
X104286Y-246781D01*
X104856Y-246864D01*
X105363Y-246781D01*
X105870Y-246364D01*
X106186Y-245864D01*
X106250Y-245364D01*
X106123Y-244781D01*
X105680Y-244364D01*
X105236Y-244197D01*
X104666D01*
G01X105236D02*
X105616Y-243947D01*
X105933Y-243531D01*
X106060Y-243031D01*
X105933Y-242531D01*
X105616Y-242114D01*
X105046Y-241864D01*
X104476Y-241947D01*
X103906Y-242281D01*
G01X110653Y-246864D02*
Y-241864D01*
X108310Y-245447D01*
X111476D01*
G01X113600Y-246114D02*
X113980Y-246531D01*
X114423Y-246781D01*
X114993Y-246864D01*
X115563Y-246697D01*
X116006Y-246364D01*
X116323Y-245781D01*
X116386Y-245114D01*
X116260Y-244447D01*
X115943Y-244031D01*
X115500Y-243697D01*
X115056Y-243614D01*
X114613Y-243697D01*
X114043Y-244031D01*
X114233Y-241864D01*
X115943D01*
G01X123990Y-246864D02*
Y-241864D01*
X126396D01*
G01X125510Y-244281D02*
X123990D01*
G01X128710Y-246864D02*
X130293Y-241864D01*
X131876Y-246864D01*
G01X131306Y-245114D02*
X129280D01*
G01X134063Y-246864D02*
X136723Y-241864D01*
G01X134063D02*
X136723Y-246864D01*
G01X140493Y-247031D02*
X140366Y-246947D01*
Y-246781D01*
X140493Y-246697D01*
X140620Y-246781D01*
Y-246947D01*
X140493Y-247031D01*
G01Y-244781D02*
X140366Y-244697D01*
Y-244531D01*
X140493Y-244447D01*
X140620Y-244531D01*
Y-244697D01*
X140493Y-244781D01*
G01X145276Y-248531D02*
X144643Y-247697D01*
X144326Y-246864D01*
Y-243531D01*
X144643Y-242697D01*
X145276Y-241864D01*
G01X150693D02*
X150186Y-242031D01*
X149806Y-242447D01*
X149553Y-242947D01*
X149363Y-243614D01*
X149300Y-244364D01*
X149363Y-245114D01*
X149553Y-245781D01*
X149806Y-246281D01*
X150186Y-246697D01*
X150693Y-246864D01*
X151200Y-246697D01*
X151580Y-246281D01*
X151833Y-245781D01*
X152023Y-245114D01*
X152086Y-244364D01*
X152023Y-243614D01*
X151833Y-242947D01*
X151580Y-242447D01*
X151200Y-242031D01*
X150693Y-241864D01*
G01X154400Y-245864D02*
X154780Y-246447D01*
X155286Y-246781D01*
X155856Y-246864D01*
X156363Y-246781D01*
X156870Y-246364D01*
X157186Y-245864D01*
X157250Y-245364D01*
X157123Y-244781D01*
X156680Y-244364D01*
X156236Y-244197D01*
X155666D01*
G01X156236D02*
X156616Y-243947D01*
X156933Y-243531D01*
X157060Y-243031D01*
X156933Y-242531D01*
X156616Y-242114D01*
X156046Y-241864D01*
X155476Y-241947D01*
X154906Y-242281D01*
G01X161210Y-248531D02*
X161843Y-247697D01*
X162160Y-246864D01*
Y-243531D01*
X161843Y-242697D01*
X161210Y-241864D01*
G01X164600Y-245864D02*
X164980Y-246447D01*
X165486Y-246781D01*
X166056Y-246864D01*
X166563Y-246781D01*
X167070Y-246364D01*
X167386Y-245864D01*
X167450Y-245364D01*
X167323Y-244781D01*
X166880Y-244364D01*
X166436Y-244197D01*
X165866D01*
G01X166436D02*
X166816Y-243947D01*
X167133Y-243531D01*
X167260Y-243031D01*
X167133Y-242531D01*
X166816Y-242114D01*
X166246Y-241864D01*
X165676Y-241947D01*
X165106Y-242281D01*
G01X170016Y-246281D02*
X170460Y-246697D01*
X170966Y-246864D01*
X171473Y-246697D01*
X171916Y-246197D01*
X172233Y-245447D01*
X172360Y-244697D01*
Y-243781D01*
X172233Y-243031D01*
X171916Y-242364D01*
X171536Y-242031D01*
X171093Y-241864D01*
X170586Y-242031D01*
X170206Y-242364D01*
X169953Y-242864D01*
X169826Y-243531D01*
X169953Y-244114D01*
X170270Y-244697D01*
X170650Y-245031D01*
X171093Y-245114D01*
X171600Y-244947D01*
X171980Y-244531D01*
X172360Y-243781D01*
G01X176066Y-246864D02*
X176193Y-245781D01*
X176383Y-244864D01*
X176636Y-244031D01*
X176953Y-243114D01*
X177460Y-241864D01*
X174926D01*
G01X180470Y-245197D02*
X182116D01*
G01X185000Y-245864D02*
X185380Y-246447D01*
X185886Y-246781D01*
X186456Y-246864D01*
X186963Y-246781D01*
X187470Y-246364D01*
X187786Y-245864D01*
X187850Y-245364D01*
X187723Y-244781D01*
X187280Y-244364D01*
X186836Y-244197D01*
X186266D01*
G01X186836D02*
X187216Y-243947D01*
X187533Y-243531D01*
X187660Y-243031D01*
X187533Y-242531D01*
X187216Y-242114D01*
X186646Y-241864D01*
X186076Y-241947D01*
X185506Y-242281D01*
G01X190290Y-244781D02*
X190733Y-244197D01*
X191113Y-243864D01*
X191620Y-243697D01*
X192063Y-243864D01*
X192380Y-244197D01*
X192633Y-244697D01*
X192696Y-245281D01*
X192633Y-245781D01*
X192380Y-246281D01*
X192000Y-246697D01*
X191556Y-246864D01*
X191050Y-246697D01*
X190606Y-246197D01*
X190353Y-245447D01*
X190290Y-244614D01*
X190416Y-243531D01*
X190606Y-242947D01*
X190923Y-242364D01*
X191366Y-241947D01*
X191810Y-241864D01*
X192253Y-242031D01*
X192570Y-242447D01*
G01X196593Y-246864D02*
Y-241864D01*
X195833Y-242864D01*
G01Y-246864D02*
X197353D01*
G01X202453D02*
Y-241864D01*
X200110Y-245447D01*
X203276D01*
G01X26493Y-176864D02*
Y-251864D01*
X526493D01*
Y-176864D01*
X26493D01*
G01X221493D02*
Y-251864D01*
G01Y-226864D02*
X324493D01*
Y-201864D01*
G01X221493D02*
X324493D01*
G01X332000Y-236864D02*
Y-231864D01*
X333266D01*
X333773Y-232114D01*
X334153Y-232447D01*
X334470Y-232947D01*
X334723Y-233531D01*
X334786Y-234364D01*
X334723Y-235197D01*
X334470Y-235781D01*
X334153Y-236281D01*
X333773Y-236614D01*
X333266Y-236864D01*
X332000D01*
G01X336910D02*
X338493Y-231864D01*
X340076Y-236864D01*
G01X339506Y-235114D02*
X337480D01*
G01X343593Y-231864D02*
Y-236864D01*
G01X342136Y-231864D02*
X345050D01*
G01X349960Y-236864D02*
X347426D01*
Y-231864D01*
X349960D01*
G01X348946Y-234281D02*
X347426D01*
G01X353793Y-237031D02*
X353666Y-236947D01*
Y-236781D01*
X353793Y-236697D01*
X353920Y-236781D01*
Y-236947D01*
X353793Y-237031D01*
G01Y-234781D02*
X353666Y-234697D01*
Y-234531D01*
X353793Y-234447D01*
X353920Y-234531D01*
Y-234697D01*
X353793Y-234781D01*
G01X326493Y-176864D02*
Y-251864D01*
G01X324493Y-176864D02*
Y-251864D01*
G01X326493Y-226864D02*
X526493D01*
G01X332126Y-211864D02*
Y-206864D01*
X333646D01*
X334153Y-207114D01*
X334533Y-207697D01*
X334660Y-208364D01*
X334533Y-209031D01*
X334216Y-209531D01*
X333646Y-209781D01*
X332126D01*
G01X337353Y-212031D02*
X339633Y-206864D01*
G01X342136Y-211864D02*
Y-206864D01*
X345050Y-211864D01*
Y-206864D01*
G01X348693Y-212031D02*
X348566Y-211947D01*
Y-211781D01*
X348693Y-211697D01*
X348820Y-211781D01*
Y-211947D01*
X348693Y-212031D01*
G01Y-209781D02*
X348566Y-209697D01*
Y-209531D01*
X348693Y-209447D01*
X348820Y-209531D01*
Y-209697D01*
X348693Y-209781D01*
G01X326493Y-201864D02*
X526493D01*
G01X332126Y-186864D02*
Y-181864D01*
X333646D01*
X334153Y-182114D01*
X334533Y-182697D01*
X334660Y-183364D01*
X334533Y-184031D01*
X334216Y-184531D01*
X333646Y-184781D01*
X332126D01*
G01X337226Y-186864D02*
Y-181864D01*
X338810D01*
X339316Y-182114D01*
X339633Y-182447D01*
X339760Y-183114D01*
X339633Y-183781D01*
X339253Y-184197D01*
X338810Y-184447D01*
X337226D01*
G01X338810D02*
X339760Y-186864D01*
G01X343593D02*
X343086Y-186781D01*
X342643Y-186447D01*
X342263Y-185947D01*
X342010Y-185364D01*
X341883Y-184697D01*
Y-184031D01*
X342010Y-183364D01*
X342263Y-182781D01*
X342643Y-182281D01*
X343086Y-181947D01*
X343593Y-181864D01*
X344100Y-181947D01*
X344543Y-182281D01*
X344923Y-182781D01*
X345176Y-183364D01*
X345303Y-184031D01*
Y-184697D01*
X345176Y-185364D01*
X344923Y-185947D01*
X344543Y-186447D01*
X344100Y-186781D01*
X343593Y-186864D01*
G01X347426Y-185864D02*
X347743Y-186364D01*
X348123Y-186697D01*
X348566Y-186864D01*
X349073Y-186697D01*
X349453Y-186364D01*
X349833Y-185864D01*
X349960Y-185197D01*
Y-181864D01*
G01X355060Y-186864D02*
X352526D01*
Y-181864D01*
X355060D01*
G01X354046Y-184281D02*
X352526D01*
G01X360286Y-182281D02*
X359906Y-182031D01*
X359463Y-181864D01*
X358956D01*
X358386Y-182114D01*
X357943Y-182531D01*
X357626Y-183031D01*
X357373Y-183864D01*
X357310Y-184614D01*
X357436Y-185364D01*
X357626Y-185864D01*
X358006Y-186364D01*
X358450Y-186697D01*
X358893Y-186864D01*
X359336D01*
X359780Y-186697D01*
X360160Y-186447D01*
X360476Y-186114D01*
G01X363993Y-181864D02*
Y-186864D01*
G01X362536Y-181864D02*
X365450D01*
G01X369093Y-187031D02*
X368966Y-186947D01*
Y-186781D01*
X369093Y-186697D01*
X369220Y-186781D01*
Y-186947D01*
X369093Y-187031D01*
G01Y-184781D02*
X368966Y-184697D01*
Y-184531D01*
X369093Y-184447D01*
X369220Y-184531D01*
Y-184697D01*
X369093Y-184781D01*
G01X447126Y-236864D02*
Y-231864D01*
X448710D01*
X449216Y-232114D01*
X449533Y-232447D01*
X449660Y-233114D01*
X449533Y-233781D01*
X449153Y-234197D01*
X448710Y-234447D01*
X447126D01*
G01X448710D02*
X449660Y-236864D01*
G01X454760D02*
X452226D01*
Y-231864D01*
X454760D01*
G01X453746Y-234281D02*
X452226D01*
G01X457010Y-231864D02*
X458593Y-236864D01*
X460176Y-231864D01*
G01X463693Y-237031D02*
X463566Y-236947D01*
Y-236781D01*
X463693Y-236697D01*
X463820Y-236781D01*
Y-236947D01*
X463693Y-237031D01*
G01Y-234781D02*
X463566Y-234697D01*
Y-234531D01*
X463693Y-234447D01*
X463820Y-234531D01*
Y-234697D01*
X463693Y-234781D01*
G01X441493Y-226864D02*
Y-251864D01*
G01X490493Y-226864D02*
Y-251864D01*
G01X-1043962Y-705877D02*
Y2342823D01*
X2300638D01*
Y-705877D01*
X-1043962D01*
G01X37198Y-238524D02*
X37825Y-239049D01*
X38530Y-239364D01*
X39156D01*
X39783Y-239049D01*
X40253Y-238524D01*
X40488Y-237789D01*
X40331Y-237054D01*
X39940Y-236424D01*
X39235Y-236004D01*
X38295Y-235794D01*
X37746Y-235374D01*
X37511Y-234639D01*
X37668Y-233904D01*
X38060Y-233379D01*
X38608Y-233064D01*
X39156D01*
X39705Y-233274D01*
X40175Y-233799D01*
G01X43498Y-239364D02*
Y-233064D01*
G01X46788D02*
Y-239364D01*
G01Y-236214D02*
X43498D01*
G01X50503Y-233064D02*
X52383D01*
G01X51443D02*
Y-239364D01*
G01X50503D02*
X52383D01*
G01X59310D02*
X56176D01*
Y-233064D01*
X59310D01*
G01X58056Y-236109D02*
X56176D01*
G01X62241Y-239364D02*
Y-233064D01*
X65845Y-239364D01*
Y-233064D01*
G01X70186Y-240519D02*
X70500Y-239154D01*
G01X76643Y-233064D02*
Y-239364D01*
G01X74841Y-233064D02*
X78445D01*
G01X80985Y-239364D02*
X82943Y-233064D01*
X84901Y-239364D01*
G01X84196Y-237159D02*
X81690D01*
G01X88303Y-233064D02*
X90183D01*
G01X89243D02*
Y-239364D01*
G01X88303D02*
X90183D01*
G01X93193Y-233064D02*
X94290Y-239364D01*
X95543Y-233064D01*
X96796Y-239364D01*
X97893Y-233064D01*
G01X99885Y-239364D02*
X101843Y-233064D01*
X103801Y-239364D01*
G01X103096Y-237159D02*
X100590D01*
G01X106341Y-239364D02*
Y-233064D01*
X109945Y-239364D01*
Y-233064D01*
G01X119176Y-239364D02*
Y-233064D01*
X121135D01*
X121761Y-233379D01*
X122153Y-233799D01*
X122310Y-234639D01*
X122153Y-235479D01*
X121683Y-236004D01*
X121135Y-236319D01*
X119176D01*
G01X121135D02*
X122310Y-239364D01*
G01X127043Y-239574D02*
X126886Y-239469D01*
Y-239259D01*
X127043Y-239154D01*
X127200Y-239259D01*
Y-239469D01*
X127043Y-239574D01*
G01X133343Y-239364D02*
X132716Y-239259D01*
X132168Y-238839D01*
X131698Y-238209D01*
X131385Y-237474D01*
X131228Y-236634D01*
Y-235794D01*
X131385Y-234954D01*
X131698Y-234219D01*
X132168Y-233589D01*
X132716Y-233169D01*
X133343Y-233064D01*
X133970Y-233169D01*
X134518Y-233589D01*
X134988Y-234219D01*
X135301Y-234954D01*
X135458Y-235794D01*
Y-236634D01*
X135301Y-237474D01*
X134988Y-238209D01*
X134518Y-238839D01*
X133970Y-239259D01*
X133343Y-239364D01*
G01X139643Y-239574D02*
X139486Y-239469D01*
Y-239259D01*
X139643Y-239154D01*
X139800Y-239259D01*
Y-239469D01*
X139643Y-239574D01*
G01X147666Y-233589D02*
X147196Y-233274D01*
X146648Y-233064D01*
X146021D01*
X145316Y-233379D01*
X144768Y-233904D01*
X144376Y-234534D01*
X144063Y-235584D01*
X143985Y-236529D01*
X144141Y-237474D01*
X144376Y-238104D01*
X144846Y-238734D01*
X145395Y-239154D01*
X145943Y-239364D01*
X146491D01*
X147040Y-239154D01*
X147510Y-238839D01*
X147901Y-238419D01*
G01X152243Y-239574D02*
X152086Y-239469D01*
Y-239259D01*
X152243Y-239154D01*
X152400Y-239259D01*
Y-239469D01*
X152243Y-239574D01*
G01X37120Y-229364D02*
Y-223064D01*
G01X40096D02*
X37120Y-226949D01*
G01X40566Y-229364D02*
X38451Y-225164D01*
G01X43420Y-223064D02*
Y-227579D01*
X43733Y-228524D01*
X44360Y-229154D01*
X45143Y-229364D01*
X45926Y-229154D01*
X46553Y-228524D01*
X46866Y-227579D01*
Y-223064D01*
G01X53010Y-229364D02*
X49876D01*
Y-223064D01*
X53010D01*
G01X51756Y-226109D02*
X49876D01*
G01X56803Y-223064D02*
X58683D01*
G01X57743D02*
Y-229364D01*
G01X56803D02*
X58683D01*
G01X68698Y-228524D02*
X69325Y-229049D01*
X70030Y-229364D01*
X70656D01*
X71283Y-229049D01*
X71753Y-228524D01*
X71988Y-227789D01*
X71831Y-227054D01*
X71440Y-226424D01*
X70735Y-226004D01*
X69795Y-225794D01*
X69246Y-225374D01*
X69011Y-224639D01*
X69168Y-223904D01*
X69560Y-223379D01*
X70108Y-223064D01*
X70656D01*
X71205Y-223274D01*
X71675Y-223799D01*
G01X74998Y-229364D02*
Y-223064D01*
G01X78288D02*
Y-229364D01*
G01Y-226214D02*
X74998D01*
G01X80985Y-229364D02*
X82943Y-223064D01*
X84901Y-229364D01*
G01X84196Y-227159D02*
X81690D01*
G01X87441Y-229364D02*
Y-223064D01*
X91045Y-229364D01*
Y-223064D01*
G01X100198Y-229364D02*
Y-223064D01*
G01X103488D02*
Y-229364D01*
G01Y-226214D02*
X100198D01*
G01X106498Y-228524D02*
X107125Y-229049D01*
X107830Y-229364D01*
X108456D01*
X109083Y-229049D01*
X109553Y-228524D01*
X109788Y-227789D01*
X109631Y-227054D01*
X109240Y-226424D01*
X108535Y-226004D01*
X107595Y-225794D01*
X107046Y-225374D01*
X106811Y-224639D01*
X106968Y-223904D01*
X107360Y-223379D01*
X107908Y-223064D01*
X108456D01*
X109005Y-223274D01*
X109475Y-223799D01*
G01X113503Y-223064D02*
X115383D01*
G01X114443D02*
Y-229364D01*
G01X113503D02*
X115383D01*
G01X118785D02*
X120743Y-223064D01*
X122701Y-229364D01*
G01X121996Y-227159D02*
X119490D01*
G01X125241Y-229364D02*
Y-223064D01*
X128845Y-229364D01*
Y-223064D01*
G01X133813Y-226214D02*
X135380D01*
Y-228104D01*
X134910Y-228734D01*
X134361Y-229154D01*
X133578Y-229364D01*
X132795Y-229154D01*
X132246Y-228734D01*
X131776Y-228104D01*
X131463Y-227369D01*
X131306Y-226529D01*
Y-225794D01*
X131463Y-225164D01*
X131776Y-224429D01*
X132246Y-223799D01*
X132716Y-223379D01*
X133343Y-223064D01*
X133891D01*
X134518Y-223274D01*
X134988Y-223694D01*
G01X139486Y-230519D02*
X139800Y-229154D01*
G01X145943Y-223064D02*
Y-229364D01*
G01X144141Y-223064D02*
X147745D01*
G01X150285Y-229364D02*
X152243Y-223064D01*
X154201Y-229364D01*
G01X153496Y-227159D02*
X150990D01*
G01X158543Y-229364D02*
X157916Y-229259D01*
X157368Y-228839D01*
X156898Y-228209D01*
X156585Y-227474D01*
X156428Y-226634D01*
Y-225794D01*
X156585Y-224954D01*
X156898Y-224219D01*
X157368Y-223589D01*
X157916Y-223169D01*
X158543Y-223064D01*
X159170Y-223169D01*
X159718Y-223589D01*
X160188Y-224219D01*
X160501Y-224954D01*
X160658Y-225794D01*
Y-226634D01*
X160501Y-227474D01*
X160188Y-228209D01*
X159718Y-228839D01*
X159170Y-229259D01*
X158543Y-229364D01*
G01X171143D02*
Y-226529D01*
X169576Y-223064D01*
G01X172710D02*
X171143Y-226529D01*
G01X175720Y-223064D02*
Y-227579D01*
X176033Y-228524D01*
X176660Y-229154D01*
X177443Y-229364D01*
X178226Y-229154D01*
X178853Y-228524D01*
X179166Y-227579D01*
Y-223064D01*
G01X181785Y-229364D02*
X183743Y-223064D01*
X185701Y-229364D01*
G01X184996Y-227159D02*
X182490D01*
G01X188241Y-229364D02*
Y-223064D01*
X191845Y-229364D01*
Y-223064D01*
G01X37041Y-219364D02*
Y-213064D01*
X40645Y-219364D01*
Y-213064D01*
G01X45143Y-219364D02*
X44516Y-219259D01*
X43968Y-218839D01*
X43498Y-218209D01*
X43185Y-217474D01*
X43028Y-216634D01*
Y-215794D01*
X43185Y-214954D01*
X43498Y-214219D01*
X43968Y-213589D01*
X44516Y-213169D01*
X45143Y-213064D01*
X45770Y-213169D01*
X46318Y-213589D01*
X46788Y-214219D01*
X47101Y-214954D01*
X47258Y-215794D01*
Y-216634D01*
X47101Y-217474D01*
X46788Y-218209D01*
X46318Y-218839D01*
X45770Y-219259D01*
X45143Y-219364D01*
G01X51443Y-219574D02*
X51286Y-219469D01*
Y-219259D01*
X51443Y-219154D01*
X51600Y-219259D01*
Y-219469D01*
X51443Y-219574D01*
G01X57743Y-219364D02*
Y-213064D01*
X56803Y-214324D01*
G01Y-219364D02*
X58683D01*
G01X64043D02*
X64591Y-219259D01*
X65218Y-218944D01*
X65610Y-218419D01*
X65766Y-217684D01*
X65610Y-216949D01*
X65140Y-216319D01*
X64435Y-216004D01*
X63651D01*
X63181Y-215794D01*
X62790Y-215269D01*
X62633Y-214534D01*
X62868Y-213799D01*
X63416Y-213274D01*
X64043Y-213064D01*
X64670Y-213274D01*
X65218Y-213799D01*
X65453Y-214534D01*
X65296Y-215269D01*
X64905Y-215794D01*
X64435Y-216004D01*
X63651D01*
X62946Y-216319D01*
X62476Y-216949D01*
X62320Y-217684D01*
X62476Y-218419D01*
X62868Y-218944D01*
X63495Y-219259D01*
X64043Y-219364D01*
G01X70343D02*
X70891Y-219259D01*
X71518Y-218944D01*
X71910Y-218419D01*
X72066Y-217684D01*
X71910Y-216949D01*
X71440Y-216319D01*
X70735Y-216004D01*
X69951D01*
X69481Y-215794D01*
X69090Y-215269D01*
X68933Y-214534D01*
X69168Y-213799D01*
X69716Y-213274D01*
X70343Y-213064D01*
X70970Y-213274D01*
X71518Y-213799D01*
X71753Y-214534D01*
X71596Y-215269D01*
X71205Y-215794D01*
X70735Y-216004D01*
X69951D01*
X69246Y-216319D01*
X68776Y-216949D01*
X68620Y-217684D01*
X68776Y-218419D01*
X69168Y-218944D01*
X69795Y-219259D01*
X70343Y-219364D01*
G01X76486Y-220519D02*
X76800Y-219154D01*
G01X80593Y-213064D02*
X81690Y-219364D01*
X82943Y-213064D01*
X84196Y-219364D01*
X85293Y-213064D01*
G01X90810Y-219364D02*
X87676D01*
Y-213064D01*
X90810D01*
G01X89556Y-216109D02*
X87676D01*
G01X93741Y-219364D02*
Y-213064D01*
X97345Y-219364D01*
Y-213064D01*
G01X106498Y-219364D02*
Y-213064D01*
G01X109788D02*
Y-219364D01*
G01Y-216214D02*
X106498D01*
G01X112093Y-213064D02*
X113190Y-219364D01*
X114443Y-213064D01*
X115696Y-219364D01*
X116793Y-213064D01*
G01X118785Y-219364D02*
X120743Y-213064D01*
X122701Y-219364D01*
G01X121996Y-217159D02*
X119490D01*
G01X131855Y-214114D02*
X132325Y-213484D01*
X132873Y-213169D01*
X133500Y-213064D01*
X134283Y-213274D01*
X134831Y-213799D01*
X134988Y-214429D01*
X134910Y-215059D01*
X134596Y-215584D01*
X133030Y-216634D01*
X132325Y-217369D01*
X131855Y-218419D01*
X131698Y-219364D01*
X134988D01*
G01X137841D02*
Y-213064D01*
X141445Y-219364D01*
Y-213064D01*
G01X144220Y-219364D02*
Y-213064D01*
X145786D01*
X146413Y-213379D01*
X146883Y-213799D01*
X147275Y-214429D01*
X147588Y-215164D01*
X147666Y-216214D01*
X147588Y-217264D01*
X147275Y-217999D01*
X146883Y-218629D01*
X146413Y-219049D01*
X145786Y-219364D01*
X144220D01*
G01X156976D02*
Y-213064D01*
X158935D01*
X159561Y-213379D01*
X159953Y-213799D01*
X160110Y-214639D01*
X159953Y-215479D01*
X159483Y-216004D01*
X158935Y-216319D01*
X156976D01*
G01X158935D02*
X160110Y-219364D01*
G01X163120D02*
Y-213064D01*
X164686D01*
X165313Y-213379D01*
X165783Y-213799D01*
X166175Y-214429D01*
X166488Y-215164D01*
X166566Y-216214D01*
X166488Y-217264D01*
X166175Y-217999D01*
X165783Y-218629D01*
X165313Y-219049D01*
X164686Y-219364D01*
X163120D01*
G01X171143Y-219574D02*
X170986Y-219469D01*
Y-219259D01*
X171143Y-219154D01*
X171300Y-219259D01*
Y-219469D01*
X171143Y-219574D01*
G01X61143Y-206664D02*
X58623Y-206247D01*
X56418Y-204581D01*
X54528Y-202081D01*
X53268Y-199164D01*
X52638Y-195831D01*
Y-192497D01*
X53268Y-189164D01*
X54528Y-186247D01*
X56418Y-183748D01*
X58623Y-182081D01*
X61143Y-181664D01*
X63663Y-182081D01*
X65868Y-183748D01*
X67758Y-186247D01*
X69018Y-189164D01*
X69648Y-192497D01*
Y-195831D01*
X69018Y-199164D01*
X67758Y-202081D01*
X65868Y-204581D01*
X63663Y-206247D01*
X61143Y-206664D01*
G01X63663Y-199997D02*
X67443Y-206664D01*
G01X80988Y-189998D02*
Y-201664D01*
X82248Y-204581D01*
X84138Y-206247D01*
X86343Y-206664D01*
X88548Y-206247D01*
X90438Y-204581D01*
X91698Y-201664D01*
G01Y-206664D02*
Y-189998D01*
G01X117213Y-206664D02*
Y-189998D01*
G01Y-192914D02*
X115953Y-191248D01*
X114063Y-190414D01*
X111858Y-189998D01*
X109653Y-190831D01*
X107763Y-192497D01*
X106503Y-194998D01*
X105873Y-198331D01*
X106503Y-201664D01*
X107763Y-204165D01*
X109653Y-205831D01*
X111858Y-206664D01*
X114063Y-206247D01*
X115953Y-204998D01*
X117213Y-203331D01*
G01X131388Y-206664D02*
Y-189998D01*
G01Y-194164D02*
X132648Y-192081D01*
X134538Y-190414D01*
X137058Y-189998D01*
X139263Y-190414D01*
X141153Y-192081D01*
X142098Y-194998D01*
Y-206664D01*
G01X161943Y-181664D02*
Y-206664D01*
G01X157533Y-189998D02*
X166353D01*
G01X192813Y-206664D02*
Y-189998D01*
G01Y-192914D02*
X191553Y-191248D01*
X189663Y-190414D01*
X187458Y-189998D01*
X185253Y-190831D01*
X183363Y-192497D01*
X182103Y-194998D01*
X181473Y-198331D01*
X182103Y-201664D01*
X183363Y-204165D01*
X185253Y-205831D01*
X187458Y-206664D01*
X189663Y-206247D01*
X191553Y-204998D01*
X192813Y-203331D01*
G01X232493Y-186364D02*
Y-194364D01*
X236493D01*
G01X244293D02*
Y-189031D01*
G01Y-189964D02*
X243893Y-189431D01*
X243293Y-189164D01*
X242593Y-189031D01*
X241893Y-189297D01*
X241293Y-189831D01*
X240893Y-190631D01*
X240693Y-191697D01*
X240893Y-192764D01*
X241293Y-193564D01*
X241893Y-194097D01*
X242593Y-194364D01*
X243293Y-194231D01*
X243893Y-193831D01*
X244293Y-193298D01*
G01X248393Y-196764D02*
X248993Y-197031D01*
X249793Y-196764D01*
X250293Y-196231D01*
X250693Y-195564D01*
X251293Y-193431D01*
X252593Y-189031D01*
G01X249393D02*
X251293Y-193431D01*
G01X256993Y-190764D02*
X260193D01*
X259893Y-189831D01*
X259393Y-189297D01*
X258693Y-189031D01*
X257993Y-189164D01*
X257393Y-189564D01*
X256993Y-190497D01*
X256793Y-191298D01*
Y-192097D01*
X256993Y-192897D01*
X257493Y-193697D01*
X258093Y-194231D01*
X258793Y-194364D01*
X259493Y-194097D01*
X260193Y-193298D01*
G01X265093Y-194364D02*
Y-189031D01*
G01Y-190097D02*
X265593Y-189564D01*
X266093Y-189164D01*
X266793Y-189031D01*
X267293Y-189164D01*
X267893Y-189564D01*
G01X254793Y-236364D02*
X257193D01*
G01X255993D02*
Y-244364D01*
G01X254793D02*
X257193D01*
G01X262593D02*
Y-239031D01*
G01Y-240097D02*
X263093Y-239564D01*
X263593Y-239164D01*
X264293Y-239031D01*
X264793Y-239164D01*
X265393Y-239564D01*
G01X270493Y-240764D02*
X273693D01*
X273393Y-239831D01*
X272893Y-239297D01*
X272193Y-239031D01*
X271493Y-239164D01*
X270893Y-239564D01*
X270493Y-240497D01*
X270293Y-241298D01*
Y-242097D01*
X270493Y-242897D01*
X270993Y-243697D01*
X271593Y-244231D01*
X272293Y-244364D01*
X272993Y-244097D01*
X273693Y-243298D01*
G01X278293Y-244364D02*
Y-239031D01*
G01Y-240364D02*
X278693Y-239697D01*
X279293Y-239164D01*
X280093Y-239031D01*
X280793Y-239164D01*
X281393Y-239697D01*
X281693Y-240631D01*
Y-244364D01*
G01X286493Y-240764D02*
X289693D01*
X289393Y-239831D01*
X288893Y-239297D01*
X288193Y-239031D01*
X287493Y-239164D01*
X286893Y-239564D01*
X286493Y-240497D01*
X286293Y-241298D01*
Y-242097D01*
X286493Y-242897D01*
X286993Y-243697D01*
X287593Y-244231D01*
X288293Y-244364D01*
X288993Y-244097D01*
X289693Y-243298D01*
G01X264093Y-215364D02*
X266093D01*
Y-217764D01*
X265493Y-218564D01*
X264793Y-219097D01*
X263793Y-219364D01*
X262793Y-219097D01*
X262093Y-218564D01*
X261493Y-217764D01*
X261093Y-216831D01*
X260893Y-215764D01*
Y-214831D01*
X261093Y-214031D01*
X261493Y-213097D01*
X262093Y-212297D01*
X262693Y-211764D01*
X263493Y-211364D01*
X264193D01*
X264993Y-211631D01*
X265593Y-212164D01*
G01X269193Y-219364D02*
Y-211364D01*
X273793Y-219364D01*
Y-211364D01*
G01X277293Y-219364D02*
Y-211364D01*
X279293D01*
X280093Y-211764D01*
X280693Y-212297D01*
X281193Y-213097D01*
X281593Y-214031D01*
X281693Y-215364D01*
X281593Y-216697D01*
X281193Y-217631D01*
X280693Y-218431D01*
X280093Y-218964D01*
X279293Y-219364D01*
X277293D01*
G01X285593Y-212697D02*
X286193Y-211897D01*
X286893Y-211497D01*
X287693Y-211364D01*
X288693Y-211631D01*
X289393Y-212297D01*
X289593Y-213097D01*
X289493Y-213898D01*
X289093Y-214564D01*
X287093Y-215897D01*
X286193Y-216831D01*
X285593Y-218164D01*
X285393Y-219364D01*
X289593D01*
G01X284093Y-191031D02*
X284793Y-190097D01*
X285393Y-189564D01*
X286193Y-189297D01*
X286893Y-189564D01*
X287393Y-190097D01*
X287793Y-190897D01*
X287893Y-191831D01*
X287793Y-192631D01*
X287393Y-193431D01*
X286793Y-194097D01*
X286093Y-194364D01*
X285293Y-194097D01*
X284593Y-193298D01*
X284193Y-192097D01*
X284093Y-190764D01*
X284293Y-189031D01*
X284593Y-188097D01*
X285093Y-187164D01*
X285793Y-186497D01*
X286493Y-186364D01*
X287193Y-186631D01*
X287693Y-187297D01*
G01X359093Y-237697D02*
X359693Y-236897D01*
X360393Y-236497D01*
X361193Y-236364D01*
X362193Y-236631D01*
X362893Y-237297D01*
X363093Y-238097D01*
X362993Y-238898D01*
X362593Y-239564D01*
X360593Y-240897D01*
X359693Y-241831D01*
X359093Y-243164D01*
X358893Y-244364D01*
X363093D01*
G01X368993Y-236364D02*
X368193Y-236631D01*
X367593Y-237297D01*
X367193Y-238097D01*
X366893Y-239164D01*
X366793Y-240364D01*
X366893Y-241564D01*
X367193Y-242631D01*
X367593Y-243431D01*
X368193Y-244097D01*
X368993Y-244364D01*
X369793Y-244097D01*
X370393Y-243431D01*
X370793Y-242631D01*
X371093Y-241564D01*
X371193Y-240364D01*
X371093Y-239164D01*
X370793Y-238097D01*
X370393Y-237297D01*
X369793Y-236631D01*
X368993Y-236364D01*
G01X376993Y-244364D02*
Y-236364D01*
X375793Y-237964D01*
G01Y-244364D02*
X378193D01*
G01X383093Y-237697D02*
X383693Y-236897D01*
X384393Y-236497D01*
X385193Y-236364D01*
X386193Y-236631D01*
X386893Y-237297D01*
X387093Y-238097D01*
X386993Y-238898D01*
X386593Y-239564D01*
X384593Y-240897D01*
X383693Y-241831D01*
X383093Y-243164D01*
X382893Y-244364D01*
X387093D01*
G01X391193Y-244631D02*
X394793Y-236364D01*
G01X400993Y-244364D02*
Y-236364D01*
X399793Y-237964D01*
G01Y-244364D02*
X402193D01*
G01X408993Y-236364D02*
X408193Y-236631D01*
X407593Y-237297D01*
X407193Y-238097D01*
X406893Y-239164D01*
X406793Y-240364D01*
X406893Y-241564D01*
X407193Y-242631D01*
X407593Y-243431D01*
X408193Y-244097D01*
X408993Y-244364D01*
X409793Y-244097D01*
X410393Y-243431D01*
X410793Y-242631D01*
X411093Y-241564D01*
X411193Y-240364D01*
X411093Y-239164D01*
X410793Y-238097D01*
X410393Y-237297D01*
X409793Y-236631D01*
X408993Y-236364D01*
G01X415193Y-244631D02*
X418793Y-236364D01*
G01X422793Y-242764D02*
X423393Y-243697D01*
X424193Y-244231D01*
X425093Y-244364D01*
X425893Y-244231D01*
X426693Y-243564D01*
X427193Y-242764D01*
X427293Y-241964D01*
X427093Y-241031D01*
X426393Y-240364D01*
X425693Y-240097D01*
X424793D01*
G01X425693D02*
X426293Y-239697D01*
X426793Y-239031D01*
X426993Y-238231D01*
X426793Y-237431D01*
X426293Y-236764D01*
X425393Y-236364D01*
X424493Y-236497D01*
X423593Y-237031D01*
G01X432993Y-244364D02*
Y-236364D01*
X431793Y-237964D01*
G01Y-244364D02*
X434193D01*
G01X358793Y-219364D02*
Y-211364D01*
X360793D01*
X361593Y-211764D01*
X362193Y-212297D01*
X362693Y-213097D01*
X363093Y-214031D01*
X363193Y-215364D01*
X363093Y-216697D01*
X362693Y-217631D01*
X362193Y-218431D01*
X361593Y-218964D01*
X360793Y-219364D01*
X358793D01*
G01X366493D02*
X368993Y-211364D01*
X371493Y-219364D01*
G01X370593Y-216564D02*
X367393D01*
G01X376993Y-211364D02*
Y-219364D01*
G01X374693Y-211364D02*
X379293D01*
G01X383093Y-216031D02*
X383793Y-215097D01*
X384393Y-214564D01*
X385193Y-214297D01*
X385893Y-214564D01*
X386393Y-215097D01*
X386793Y-215897D01*
X386893Y-216831D01*
X386793Y-217631D01*
X386393Y-218431D01*
X385793Y-219097D01*
X385093Y-219364D01*
X384293Y-219097D01*
X383593Y-218298D01*
X383193Y-217097D01*
X383093Y-215764D01*
X383293Y-214031D01*
X383593Y-213097D01*
X384093Y-212164D01*
X384793Y-211497D01*
X385493Y-211364D01*
X386193Y-211631D01*
X386693Y-212297D01*
G01X390393Y-219364D02*
Y-211364D01*
X392993Y-218031D01*
X395593Y-211364D01*
Y-219364D01*
G01X400993Y-211364D02*
Y-219364D01*
G01X398693Y-211364D02*
X403293D01*
G01X406893Y-219364D02*
Y-211364D01*
G01X411093D02*
Y-219364D01*
G01Y-215364D02*
X406893D01*
G01X414793Y-217764D02*
X415393Y-218697D01*
X416193Y-219231D01*
X417093Y-219364D01*
X417893Y-219231D01*
X418693Y-218564D01*
X419193Y-217764D01*
X419293Y-216964D01*
X419093Y-216031D01*
X418393Y-215364D01*
X417693Y-215097D01*
X416793D01*
G01X417693D02*
X418293Y-214697D01*
X418793Y-214031D01*
X418993Y-213231D01*
X418793Y-212431D01*
X418293Y-211764D01*
X417393Y-211364D01*
X416493Y-211497D01*
X415593Y-212031D01*
G01X422493Y-219364D02*
X424993Y-211364D01*
X427493Y-219364D01*
G01X426593Y-216564D02*
X423393D01*
G01X430793Y-219364D02*
Y-211364D01*
X432793D01*
X433593Y-211764D01*
X434193Y-212297D01*
X434693Y-213097D01*
X435093Y-214031D01*
X435193Y-215364D01*
X435093Y-216697D01*
X434693Y-217631D01*
X434193Y-218431D01*
X433593Y-218964D01*
X432793Y-219364D01*
X430793D01*
G01X440993Y-211364D02*
X440193Y-211631D01*
X439593Y-212297D01*
X439193Y-213097D01*
X438893Y-214164D01*
X438793Y-215364D01*
X438893Y-216564D01*
X439193Y-217631D01*
X439593Y-218431D01*
X440193Y-219097D01*
X440993Y-219364D01*
X441793Y-219097D01*
X442393Y-218431D01*
X442793Y-217631D01*
X443093Y-216564D01*
X443193Y-215364D01*
X443093Y-214164D01*
X442793Y-213097D01*
X442393Y-212297D01*
X441793Y-211631D01*
X440993Y-211364D01*
G01X380993Y-186364D02*
Y-194364D01*
G01X378693Y-186364D02*
X383293D01*
G01X387093Y-191031D02*
X387793Y-190097D01*
X388393Y-189564D01*
X389193Y-189297D01*
X389893Y-189564D01*
X390393Y-190097D01*
X390793Y-190897D01*
X390893Y-191831D01*
X390793Y-192631D01*
X390393Y-193431D01*
X389793Y-194097D01*
X389093Y-194364D01*
X388293Y-194097D01*
X387593Y-193298D01*
X387193Y-192097D01*
X387093Y-190764D01*
X387293Y-189031D01*
X387593Y-188097D01*
X388093Y-187164D01*
X388793Y-186497D01*
X389493Y-186364D01*
X390193Y-186631D01*
X390693Y-187297D01*
G01X394393Y-194364D02*
Y-186364D01*
X396993Y-193031D01*
X399593Y-186364D01*
Y-194364D01*
G01X401993Y-197031D02*
X407993D01*
G01X415193Y-187031D02*
X414593Y-186631D01*
X413893Y-186364D01*
X413093D01*
X412193Y-186764D01*
X411493Y-187431D01*
X410993Y-188231D01*
X410593Y-189564D01*
X410493Y-190764D01*
X410693Y-191964D01*
X410993Y-192764D01*
X411593Y-193564D01*
X412293Y-194097D01*
X412993Y-194364D01*
X413693D01*
X414393Y-194097D01*
X414993Y-193697D01*
X415493Y-193164D01*
G01X418393Y-194364D02*
Y-186364D01*
X420993Y-193031D01*
X423593Y-186364D01*
Y-194364D01*
G01X425993Y-197031D02*
X431993D01*
G01X434793Y-194364D02*
Y-186364D01*
X436793D01*
X437593Y-186764D01*
X438193Y-187297D01*
X438693Y-188097D01*
X439093Y-189031D01*
X439193Y-190364D01*
X439093Y-191697D01*
X438693Y-192631D01*
X438193Y-193431D01*
X437593Y-193964D01*
X436793Y-194364D01*
X434793D01*
G01X473793Y-244364D02*
Y-236364D01*
X475793D01*
X476593Y-236764D01*
X477193Y-237297D01*
X477693Y-238097D01*
X478093Y-239031D01*
X478193Y-240364D01*
X478093Y-241697D01*
X477693Y-242631D01*
X477193Y-243431D01*
X476593Y-243964D01*
X475793Y-244364D01*
X473793D01*
G01X503493D02*
Y-236364D01*
X502293Y-237964D01*
G01Y-244364D02*
X504693D01*
G01X509593Y-241031D02*
X510293Y-240097D01*
X510893Y-239564D01*
X511693Y-239297D01*
X512393Y-239564D01*
X512893Y-240097D01*
X513293Y-240897D01*
X513393Y-241831D01*
X513293Y-242631D01*
X512893Y-243431D01*
X512293Y-244097D01*
X511593Y-244364D01*
X510793Y-244097D01*
X510093Y-243298D01*
X509693Y-242097D01*
X509593Y-240764D01*
X509793Y-239031D01*
X510093Y-238097D01*
X510593Y-237164D01*
X511293Y-236497D01*
X511993Y-236364D01*
X512693Y-236631D01*
X513193Y-237297D01*
M02*
